FILE_TYPE = MACRO_DRAWING;
SET COLOR_WIRE YELLOW;
SET COLOR_PROP ORANGE;
SET COLOR_DOT WHITE;
SET COLOR_ARC YELLOW;
SET COLOR_BODY GREEN;
SET COLOR_NOTE PURPLE;
SET PROP_DISPLAY VALUE;
SET PAGE_NUMBER P108;
FORCEADD TAP..1
(-5950 4450);
FORCEPROP 3 LASTPIN (-6000 4450) SIG_NAME M_L_CPU1_SA_DQ<12>
J 0
(-5990 4460);
DISPLAY 0.659574 (-5990 4460);
PAINT MONO (-5990 4460);
DISPLAY INVISIBLE (-5990 4460);
FORCEPROP 1 LASTPIN (-6000 4450) BN 12
J 0
(-6012 4458);
DISPLAY 0.489362 (-6012 4458);
PAINT GREEN (-6012 4458);
FORCEPROP 2 LAST CDS_LIB mstr_standard
J 0
(-5950 4450);
DISPLAY 0.723404 (-5950 4450);
PAINT MONO (-5950 4450);
DISPLAY INVISIBLE (-5950 4450);
FORCEPROP 1 LAST BODY_TYPE PLUMBING
J 0
(-5950 4500);
DISPLAY 0.872340 (-5950 4500);
PAINT GREEN (-5950 4500);
DISPLAY INVISIBLE (-5950 4500);
FORCEPROP 1 LAST HDL_TAP TRUE
J 0
(-5625 4325);
DISPLAY 0.872340 (-5625 4325);
DISPLAY INVISIBLE (-5625 4325);
FORCEPROP 1 LAST PATH I100
J 0
(-5952 4450);
DISPLAY 0.872340 (-5952 4450);
PAINT GREEN (-5952 4450);
DISPLAY INVISIBLE (-5952 4450);
FORCEADD TAP..1
(-5950 4400);
FORCEPROP 3 LASTPIN (-6000 4400) SIG_NAME M_L_CPU1_SA_DQ<11>
J 0
(-5990 4410);
DISPLAY 0.659574 (-5990 4410);
PAINT MONO (-5990 4410);
DISPLAY INVISIBLE (-5990 4410);
FORCEPROP 1 LASTPIN (-6000 4400) BN 11
J 0
(-6012 4408);
DISPLAY 0.489362 (-6012 4408);
PAINT GREEN (-6012 4408);
FORCEPROP 2 LAST CDS_LIB mstr_standard
J 0
(-5950 4400);
DISPLAY 0.723404 (-5950 4400);
PAINT MONO (-5950 4400);
DISPLAY INVISIBLE (-5950 4400);
FORCEPROP 1 LAST BODY_TYPE PLUMBING
J 0
(-5950 4450);
DISPLAY 0.872340 (-5950 4450);
PAINT GREEN (-5950 4450);
DISPLAY INVISIBLE (-5950 4450);
FORCEPROP 1 LAST HDL_TAP TRUE
J 0
(-5625 4275);
DISPLAY 0.872340 (-5625 4275);
DISPLAY INVISIBLE (-5625 4275);
FORCEPROP 1 LAST PATH I101
J 0
(-5952 4400);
DISPLAY 0.872340 (-5952 4400);
PAINT GREEN (-5952 4400);
DISPLAY INVISIBLE (-5952 4400);
FORCEADD TAP..1
(-5950 4350);
FORCEPROP 3 LASTPIN (-6000 4350) SIG_NAME M_L_CPU1_SA_DQ<10>
J 0
(-5990 4360);
DISPLAY 0.659574 (-5990 4360);
PAINT MONO (-5990 4360);
DISPLAY INVISIBLE (-5990 4360);
FORCEPROP 1 LASTPIN (-6000 4350) BN 10
J 0
(-6012 4358);
DISPLAY 0.489362 (-6012 4358);
PAINT GREEN (-6012 4358);
FORCEPROP 2 LAST CDS_LIB mstr_standard
J 0
(-5950 4350);
DISPLAY 0.723404 (-5950 4350);
PAINT MONO (-5950 4350);
DISPLAY INVISIBLE (-5950 4350);
FORCEPROP 1 LAST BODY_TYPE PLUMBING
J 0
(-5950 4400);
DISPLAY 0.872340 (-5950 4400);
PAINT GREEN (-5950 4400);
DISPLAY INVISIBLE (-5950 4400);
FORCEPROP 1 LAST HDL_TAP TRUE
J 0
(-5625 4225);
DISPLAY 0.872340 (-5625 4225);
DISPLAY INVISIBLE (-5625 4225);
FORCEPROP 1 LAST PATH I102
J 0
(-5952 4350);
DISPLAY 0.872340 (-5952 4350);
PAINT GREEN (-5952 4350);
DISPLAY INVISIBLE (-5952 4350);
FORCEADD TAP..1
(-5950 4300);
FORCEPROP 3 LASTPIN (-6000 4300) SIG_NAME M_L_CPU1_SA_DQ<9>
J 0
(-5990 4310);
DISPLAY 0.659574 (-5990 4310);
PAINT MONO (-5990 4310);
DISPLAY INVISIBLE (-5990 4310);
FORCEPROP 1 LASTPIN (-6000 4300) BN 9
J 0
(-6012 4308);
DISPLAY 0.489362 (-6012 4308);
PAINT GREEN (-6012 4308);
FORCEPROP 2 LAST CDS_LIB mstr_standard
J 0
(-5950 4300);
DISPLAY 0.723404 (-5950 4300);
PAINT MONO (-5950 4300);
DISPLAY INVISIBLE (-5950 4300);
FORCEPROP 1 LAST BODY_TYPE PLUMBING
J 0
(-5950 4350);
DISPLAY 0.872340 (-5950 4350);
PAINT GREEN (-5950 4350);
DISPLAY INVISIBLE (-5950 4350);
FORCEPROP 1 LAST HDL_TAP TRUE
J 0
(-5625 4175);
DISPLAY 0.872340 (-5625 4175);
DISPLAY INVISIBLE (-5625 4175);
FORCEPROP 1 LAST PATH I103
J 0
(-5952 4300);
DISPLAY 0.872340 (-5952 4300);
PAINT GREEN (-5952 4300);
DISPLAY INVISIBLE (-5952 4300);
FORCEADD TAP..1
(-5950 4250);
FORCEPROP 3 LASTPIN (-6000 4250) SIG_NAME M_L_CPU1_SA_DQ<8>
J 0
(-5990 4260);
DISPLAY 0.659574 (-5990 4260);
PAINT MONO (-5990 4260);
DISPLAY INVISIBLE (-5990 4260);
FORCEPROP 1 LASTPIN (-6000 4250) BN 8
J 0
(-6012 4258);
DISPLAY 0.489362 (-6012 4258);
PAINT GREEN (-6012 4258);
FORCEPROP 2 LAST CDS_LIB mstr_standard
J 0
(-5950 4250);
DISPLAY 0.723404 (-5950 4250);
PAINT MONO (-5950 4250);
DISPLAY INVISIBLE (-5950 4250);
FORCEPROP 1 LAST BODY_TYPE PLUMBING
J 0
(-5950 4300);
DISPLAY 0.872340 (-5950 4300);
PAINT GREEN (-5950 4300);
DISPLAY INVISIBLE (-5950 4300);
FORCEPROP 1 LAST HDL_TAP TRUE
J 0
(-5625 4125);
DISPLAY 0.872340 (-5625 4125);
DISPLAY INVISIBLE (-5625 4125);
FORCEPROP 1 LAST PATH I104
J 0
(-5952 4250);
DISPLAY 0.872340 (-5952 4250);
PAINT GREEN (-5952 4250);
DISPLAY INVISIBLE (-5952 4250);
FORCEADD TAP..1
(-5950 4600);
FORCEPROP 3 LASTPIN (-6000 4600) SIG_NAME M_L_CPU1_SA_DQ<15>
J 0
(-5990 4610);
DISPLAY 0.659574 (-5990 4610);
PAINT MONO (-5990 4610);
DISPLAY INVISIBLE (-5990 4610);
FORCEPROP 1 LASTPIN (-6000 4600) BN 15
J 0
(-6012 4608);
DISPLAY 0.489362 (-6012 4608);
PAINT GREEN (-6012 4608);
FORCEPROP 2 LAST CDS_LIB mstr_standard
J 0
(-5950 4600);
DISPLAY 0.723404 (-5950 4600);
PAINT MONO (-5950 4600);
DISPLAY INVISIBLE (-5950 4600);
FORCEPROP 1 LAST BODY_TYPE PLUMBING
J 0
(-5950 4650);
DISPLAY 0.872340 (-5950 4650);
PAINT GREEN (-5950 4650);
DISPLAY INVISIBLE (-5950 4650);
FORCEPROP 1 LAST HDL_TAP TRUE
J 0
(-5625 4475);
DISPLAY 0.872340 (-5625 4475);
DISPLAY INVISIBLE (-5625 4475);
FORCEPROP 1 LAST PATH I105
J 0
(-5952 4600);
DISPLAY 0.872340 (-5952 4600);
PAINT GREEN (-5952 4600);
DISPLAY INVISIBLE (-5952 4600);
FORCEADD TAP..1
(-5950 4650);
FORCEPROP 3 LASTPIN (-6000 4650) SIG_NAME M_L_CPU1_SA_DQ<16>
J 0
(-5990 4660);
DISPLAY 0.659574 (-5990 4660);
PAINT MONO (-5990 4660);
DISPLAY INVISIBLE (-5990 4660);
FORCEPROP 1 LASTPIN (-6000 4650) BN 16
J 0
(-6012 4658);
DISPLAY 0.489362 (-6012 4658);
PAINT GREEN (-6012 4658);
FORCEPROP 2 LAST CDS_LIB mstr_standard
J 0
(-5950 4650);
DISPLAY 0.723404 (-5950 4650);
PAINT MONO (-5950 4650);
DISPLAY INVISIBLE (-5950 4650);
FORCEPROP 1 LAST BODY_TYPE PLUMBING
J 0
(-5950 4700);
DISPLAY 0.872340 (-5950 4700);
PAINT GREEN (-5950 4700);
DISPLAY INVISIBLE (-5950 4700);
FORCEPROP 1 LAST HDL_TAP TRUE
J 0
(-5625 4525);
DISPLAY 0.872340 (-5625 4525);
DISPLAY INVISIBLE (-5625 4525);
FORCEPROP 1 LAST PATH I106
J 0
(-5952 4650);
DISPLAY 0.872340 (-5952 4650);
PAINT GREEN (-5952 4650);
DISPLAY INVISIBLE (-5952 4650);
FORCEADD TAP..1
(-5950 4700);
FORCEPROP 3 LASTPIN (-6000 4700) SIG_NAME M_L_CPU1_SA_DQ<17>
J 0
(-5990 4710);
DISPLAY 0.659574 (-5990 4710);
PAINT MONO (-5990 4710);
DISPLAY INVISIBLE (-5990 4710);
FORCEPROP 1 LASTPIN (-6000 4700) BN 17
J 0
(-6012 4708);
DISPLAY 0.489362 (-6012 4708);
PAINT GREEN (-6012 4708);
FORCEPROP 2 LAST CDS_LIB mstr_standard
J 0
(-5950 4700);
DISPLAY 0.723404 (-5950 4700);
PAINT MONO (-5950 4700);
DISPLAY INVISIBLE (-5950 4700);
FORCEPROP 1 LAST BODY_TYPE PLUMBING
J 0
(-5950 4750);
DISPLAY 0.872340 (-5950 4750);
PAINT GREEN (-5950 4750);
DISPLAY INVISIBLE (-5950 4750);
FORCEPROP 1 LAST HDL_TAP TRUE
J 0
(-5625 4575);
DISPLAY 0.872340 (-5625 4575);
DISPLAY INVISIBLE (-5625 4575);
FORCEPROP 1 LAST PATH I107
J 0
(-5952 4700);
DISPLAY 0.872340 (-5952 4700);
PAINT GREEN (-5952 4700);
DISPLAY INVISIBLE (-5952 4700);
FORCEADD TAP..1
(-5950 4550);
FORCEPROP 3 LASTPIN (-6000 4550) SIG_NAME M_L_CPU1_SA_DQ<14>
J 0
(-5990 4560);
DISPLAY 0.659574 (-5990 4560);
PAINT MONO (-5990 4560);
DISPLAY INVISIBLE (-5990 4560);
FORCEPROP 1 LASTPIN (-6000 4550) BN 14
J 0
(-6012 4558);
DISPLAY 0.489362 (-6012 4558);
PAINT GREEN (-6012 4558);
FORCEPROP 2 LAST CDS_LIB mstr_standard
J 0
(-5950 4550);
DISPLAY 0.723404 (-5950 4550);
PAINT MONO (-5950 4550);
DISPLAY INVISIBLE (-5950 4550);
FORCEPROP 1 LAST BODY_TYPE PLUMBING
J 0
(-5950 4600);
DISPLAY 0.872340 (-5950 4600);
PAINT GREEN (-5950 4600);
DISPLAY INVISIBLE (-5950 4600);
FORCEPROP 1 LAST HDL_TAP TRUE
J 0
(-5625 4425);
DISPLAY 0.872340 (-5625 4425);
DISPLAY INVISIBLE (-5625 4425);
FORCEPROP 1 LAST PATH I108
J 0
(-5952 4550);
DISPLAY 0.872340 (-5952 4550);
PAINT GREEN (-5952 4550);
DISPLAY INVISIBLE (-5952 4550);
FORCEADD TAP..1
(-5950 4500);
FORCEPROP 3 LASTPIN (-6000 4500) SIG_NAME M_L_CPU1_SA_DQ<13>
J 0
(-5990 4510);
DISPLAY 0.659574 (-5990 4510);
PAINT MONO (-5990 4510);
DISPLAY INVISIBLE (-5990 4510);
FORCEPROP 1 LASTPIN (-6000 4500) BN 13
J 0
(-6012 4508);
DISPLAY 0.489362 (-6012 4508);
PAINT GREEN (-6012 4508);
FORCEPROP 2 LAST CDS_LIB mstr_standard
J 0
(-5950 4500);
DISPLAY 0.723404 (-5950 4500);
PAINT MONO (-5950 4500);
DISPLAY INVISIBLE (-5950 4500);
FORCEPROP 1 LAST BODY_TYPE PLUMBING
J 0
(-5950 4550);
DISPLAY 0.872340 (-5950 4550);
PAINT GREEN (-5950 4550);
DISPLAY INVISIBLE (-5950 4550);
FORCEPROP 1 LAST HDL_TAP TRUE
J 0
(-5625 4375);
DISPLAY 0.872340 (-5625 4375);
DISPLAY INVISIBLE (-5625 4375);
FORCEPROP 1 LAST PATH I109
J 0
(-5952 4500);
DISPLAY 0.872340 (-5952 4500);
PAINT GREEN (-5952 4500);
DISPLAY INVISIBLE (-5952 4500);
FORCEADD OFFPAGE..6
(-8250 4050);
FORCEPROP 2 LAST $XR0 48 
J 0
(-8529 4050);
DISPLAY 0.638298 (-8529 4050);
PAINT MONO (-8529 4050);
FORCEPROP 2 LAST CDS_LIB mstr_standard
J 0
(-8250 4050);
DISPLAY 0.723404 (-8250 4050);
PAINT MONO (-8250 4050);
DISPLAY INVISIBLE (-8250 4050);
FORCEPROP 1 LAST OFFPAGE TRUE
J 0
(-7925 3925);
DISPLAY 0.872340 (-7925 3925);
PAINT GREEN (-7925 3925);
DISPLAY INVISIBLE (-7925 3925);
FORCEPROP 1 LAST COMMENT_BODY TRUE
J 0
(-8150 3975);
DISPLAY 0.872340 (-8150 3975);
PAINT GREEN (-8150 3975);
DISPLAY INVISIBLE (-8150 3975);
FORCEPROP 2 LAST PATH I11
J 0
(-8475 4100);
DISPLAY 1.021277 (-8475 4100);
DISPLAY INVISIBLE (-8475 4100);
FORCEADD TAP..1
(-5950 4900);
FORCEPROP 3 LASTPIN (-6000 4900) SIG_NAME M_L_CPU1_SA_DQ<21>
J 0
(-5990 4910);
DISPLAY 0.659574 (-5990 4910);
PAINT MONO (-5990 4910);
DISPLAY INVISIBLE (-5990 4910);
FORCEPROP 1 LASTPIN (-6000 4900) BN 21
J 0
(-6012 4908);
DISPLAY 0.489362 (-6012 4908);
PAINT GREEN (-6012 4908);
FORCEPROP 2 LAST CDS_LIB mstr_standard
J 0
(-5950 4900);
DISPLAY 0.723404 (-5950 4900);
PAINT MONO (-5950 4900);
DISPLAY INVISIBLE (-5950 4900);
FORCEPROP 1 LAST BODY_TYPE PLUMBING
J 0
(-5950 4950);
DISPLAY 0.872340 (-5950 4950);
PAINT GREEN (-5950 4950);
DISPLAY INVISIBLE (-5950 4950);
FORCEPROP 1 LAST HDL_TAP TRUE
J 0
(-5625 4775);
DISPLAY 0.872340 (-5625 4775);
DISPLAY INVISIBLE (-5625 4775);
FORCEPROP 1 LAST PATH I110
J 0
(-5952 4900);
DISPLAY 0.872340 (-5952 4900);
PAINT GREEN (-5952 4900);
DISPLAY INVISIBLE (-5952 4900);
FORCEADD TAP..1
(-5950 4950);
FORCEPROP 3 LASTPIN (-6000 4950) SIG_NAME M_L_CPU1_SA_DQ<22>
J 0
(-5990 4960);
DISPLAY 0.659574 (-5990 4960);
PAINT MONO (-5990 4960);
DISPLAY INVISIBLE (-5990 4960);
FORCEPROP 1 LASTPIN (-6000 4950) BN 22
J 0
(-6012 4958);
DISPLAY 0.489362 (-6012 4958);
PAINT GREEN (-6012 4958);
FORCEPROP 2 LAST CDS_LIB mstr_standard
J 0
(-5950 4950);
DISPLAY 0.723404 (-5950 4950);
PAINT MONO (-5950 4950);
DISPLAY INVISIBLE (-5950 4950);
FORCEPROP 1 LAST BODY_TYPE PLUMBING
J 0
(-5950 5000);
DISPLAY 0.872340 (-5950 5000);
PAINT GREEN (-5950 5000);
DISPLAY INVISIBLE (-5950 5000);
FORCEPROP 1 LAST HDL_TAP TRUE
J 0
(-5625 4825);
DISPLAY 0.872340 (-5625 4825);
DISPLAY INVISIBLE (-5625 4825);
FORCEPROP 1 LAST PATH I111
J 0
(-5952 4950);
DISPLAY 0.872340 (-5952 4950);
PAINT GREEN (-5952 4950);
DISPLAY INVISIBLE (-5952 4950);
FORCEADD TAP..1
(-5950 4850);
FORCEPROP 3 LASTPIN (-6000 4850) SIG_NAME M_L_CPU1_SA_DQ<20>
J 0
(-5990 4860);
DISPLAY 0.659574 (-5990 4860);
PAINT MONO (-5990 4860);
DISPLAY INVISIBLE (-5990 4860);
FORCEPROP 1 LASTPIN (-6000 4850) BN 20
J 0
(-6012 4858);
DISPLAY 0.489362 (-6012 4858);
PAINT GREEN (-6012 4858);
FORCEPROP 2 LAST CDS_LIB mstr_standard
J 0
(-5950 4850);
DISPLAY 0.723404 (-5950 4850);
PAINT MONO (-5950 4850);
DISPLAY INVISIBLE (-5950 4850);
FORCEPROP 1 LAST BODY_TYPE PLUMBING
J 0
(-5950 4900);
DISPLAY 0.872340 (-5950 4900);
PAINT GREEN (-5950 4900);
DISPLAY INVISIBLE (-5950 4900);
FORCEPROP 1 LAST HDL_TAP TRUE
J 0
(-5625 4725);
DISPLAY 0.872340 (-5625 4725);
DISPLAY INVISIBLE (-5625 4725);
FORCEPROP 1 LAST PATH I112
J 0
(-5952 4850);
DISPLAY 0.872340 (-5952 4850);
PAINT GREEN (-5952 4850);
DISPLAY INVISIBLE (-5952 4850);
FORCEADD TAP..1
(-5950 4800);
FORCEPROP 3 LASTPIN (-6000 4800) SIG_NAME M_L_CPU1_SA_DQ<19>
J 0
(-5990 4810);
DISPLAY 0.659574 (-5990 4810);
PAINT MONO (-5990 4810);
DISPLAY INVISIBLE (-5990 4810);
FORCEPROP 1 LASTPIN (-6000 4800) BN 19
J 0
(-6012 4808);
DISPLAY 0.489362 (-6012 4808);
PAINT GREEN (-6012 4808);
FORCEPROP 2 LAST CDS_LIB mstr_standard
J 0
(-5950 4800);
DISPLAY 0.723404 (-5950 4800);
PAINT MONO (-5950 4800);
DISPLAY INVISIBLE (-5950 4800);
FORCEPROP 1 LAST BODY_TYPE PLUMBING
J 0
(-5950 4850);
DISPLAY 0.872340 (-5950 4850);
PAINT GREEN (-5950 4850);
DISPLAY INVISIBLE (-5950 4850);
FORCEPROP 1 LAST HDL_TAP TRUE
J 0
(-5625 4675);
DISPLAY 0.872340 (-5625 4675);
DISPLAY INVISIBLE (-5625 4675);
FORCEPROP 1 LAST PATH I113
J 0
(-5952 4800);
DISPLAY 0.872340 (-5952 4800);
PAINT GREEN (-5952 4800);
DISPLAY INVISIBLE (-5952 4800);
FORCEADD TAP..1
(-5950 4750);
FORCEPROP 3 LASTPIN (-6000 4750) SIG_NAME M_L_CPU1_SA_DQ<18>
J 0
(-5990 4760);
DISPLAY 0.659574 (-5990 4760);
PAINT MONO (-5990 4760);
DISPLAY INVISIBLE (-5990 4760);
FORCEPROP 1 LASTPIN (-6000 4750) BN 18
J 0
(-6012 4758);
DISPLAY 0.489362 (-6012 4758);
PAINT GREEN (-6012 4758);
FORCEPROP 2 LAST CDS_LIB mstr_standard
J 0
(-5950 4750);
DISPLAY 0.723404 (-5950 4750);
PAINT MONO (-5950 4750);
DISPLAY INVISIBLE (-5950 4750);
FORCEPROP 1 LAST BODY_TYPE PLUMBING
J 0
(-5950 4800);
DISPLAY 0.872340 (-5950 4800);
PAINT GREEN (-5950 4800);
DISPLAY INVISIBLE (-5950 4800);
FORCEPROP 1 LAST HDL_TAP TRUE
J 0
(-5625 4625);
DISPLAY 0.872340 (-5625 4625);
DISPLAY INVISIBLE (-5625 4625);
FORCEPROP 1 LAST PATH I114
J 0
(-5952 4750);
DISPLAY 0.872340 (-5952 4750);
PAINT GREEN (-5952 4750);
DISPLAY INVISIBLE (-5952 4750);
FORCEADD TAP..1
(-5950 5150);
FORCEPROP 3 LASTPIN (-6000 5150) SIG_NAME M_L_CPU1_SA_DQ<26>
J 0
(-5990 5160);
DISPLAY 0.659574 (-5990 5160);
PAINT MONO (-5990 5160);
DISPLAY INVISIBLE (-5990 5160);
FORCEPROP 1 LASTPIN (-6000 5150) BN 26
J 0
(-6012 5158);
DISPLAY 0.489362 (-6012 5158);
PAINT GREEN (-6012 5158);
FORCEPROP 2 LAST CDS_LIB mstr_standard
J 0
(-5950 5150);
DISPLAY 0.723404 (-5950 5150);
PAINT MONO (-5950 5150);
DISPLAY INVISIBLE (-5950 5150);
FORCEPROP 1 LAST BODY_TYPE PLUMBING
J 0
(-5950 5200);
DISPLAY 0.872340 (-5950 5200);
PAINT GREEN (-5950 5200);
DISPLAY INVISIBLE (-5950 5200);
FORCEPROP 1 LAST HDL_TAP TRUE
J 0
(-5625 5025);
DISPLAY 0.872340 (-5625 5025);
DISPLAY INVISIBLE (-5625 5025);
FORCEPROP 1 LAST PATH I115
J 0
(-5952 5150);
DISPLAY 0.872340 (-5952 5150);
PAINT GREEN (-5952 5150);
DISPLAY INVISIBLE (-5952 5150);
FORCEADD TAP..1
(-5950 5200);
FORCEPROP 3 LASTPIN (-6000 5200) SIG_NAME M_L_CPU1_SA_DQ<27>
J 0
(-5990 5210);
DISPLAY 0.659574 (-5990 5210);
PAINT MONO (-5990 5210);
DISPLAY INVISIBLE (-5990 5210);
FORCEPROP 1 LASTPIN (-6000 5200) BN 27
J 0
(-6012 5208);
DISPLAY 0.489362 (-6012 5208);
PAINT GREEN (-6012 5208);
FORCEPROP 2 LAST CDS_LIB mstr_standard
J 0
(-5950 5200);
DISPLAY 0.723404 (-5950 5200);
PAINT MONO (-5950 5200);
DISPLAY INVISIBLE (-5950 5200);
FORCEPROP 1 LAST BODY_TYPE PLUMBING
J 0
(-5950 5250);
DISPLAY 0.872340 (-5950 5250);
PAINT GREEN (-5950 5250);
DISPLAY INVISIBLE (-5950 5250);
FORCEPROP 1 LAST HDL_TAP TRUE
J 0
(-5625 5075);
DISPLAY 0.872340 (-5625 5075);
DISPLAY INVISIBLE (-5625 5075);
FORCEPROP 1 LAST PATH I116
J 0
(-5952 5200);
DISPLAY 0.872340 (-5952 5200);
PAINT GREEN (-5952 5200);
DISPLAY INVISIBLE (-5952 5200);
FORCEADD TAP..1
(-5950 5100);
FORCEPROP 3 LASTPIN (-6000 5100) SIG_NAME M_L_CPU1_SA_DQ<25>
J 0
(-5990 5110);
DISPLAY 0.659574 (-5990 5110);
PAINT MONO (-5990 5110);
DISPLAY INVISIBLE (-5990 5110);
FORCEPROP 1 LASTPIN (-6000 5100) BN 25
J 0
(-6012 5108);
DISPLAY 0.489362 (-6012 5108);
PAINT GREEN (-6012 5108);
FORCEPROP 2 LAST CDS_LIB mstr_standard
J 0
(-5950 5100);
DISPLAY 0.723404 (-5950 5100);
PAINT MONO (-5950 5100);
DISPLAY INVISIBLE (-5950 5100);
FORCEPROP 1 LAST BODY_TYPE PLUMBING
J 0
(-5950 5150);
DISPLAY 0.872340 (-5950 5150);
PAINT GREEN (-5950 5150);
DISPLAY INVISIBLE (-5950 5150);
FORCEPROP 1 LAST HDL_TAP TRUE
J 0
(-5625 4975);
DISPLAY 0.872340 (-5625 4975);
DISPLAY INVISIBLE (-5625 4975);
FORCEPROP 1 LAST PATH I117
J 0
(-5952 5100);
DISPLAY 0.872340 (-5952 5100);
PAINT GREEN (-5952 5100);
DISPLAY INVISIBLE (-5952 5100);
FORCEADD TAP..1
(-5950 5050);
FORCEPROP 3 LASTPIN (-6000 5050) SIG_NAME M_L_CPU1_SA_DQ<24>
J 0
(-5990 5060);
DISPLAY 0.659574 (-5990 5060);
PAINT MONO (-5990 5060);
DISPLAY INVISIBLE (-5990 5060);
FORCEPROP 1 LASTPIN (-6000 5050) BN 24
J 0
(-6012 5058);
DISPLAY 0.489362 (-6012 5058);
PAINT GREEN (-6012 5058);
FORCEPROP 2 LAST CDS_LIB mstr_standard
J 0
(-5950 5050);
DISPLAY 0.723404 (-5950 5050);
PAINT MONO (-5950 5050);
DISPLAY INVISIBLE (-5950 5050);
FORCEPROP 1 LAST BODY_TYPE PLUMBING
J 0
(-5950 5100);
DISPLAY 0.872340 (-5950 5100);
PAINT GREEN (-5950 5100);
DISPLAY INVISIBLE (-5950 5100);
FORCEPROP 1 LAST HDL_TAP TRUE
J 0
(-5625 4925);
DISPLAY 0.872340 (-5625 4925);
DISPLAY INVISIBLE (-5625 4925);
FORCEPROP 1 LAST PATH I118
J 0
(-5952 5050);
DISPLAY 0.872340 (-5952 5050);
PAINT GREEN (-5952 5050);
DISPLAY INVISIBLE (-5952 5050);
FORCEADD TAP..1
(-5950 5000);
FORCEPROP 3 LASTPIN (-6000 5000) SIG_NAME M_L_CPU1_SA_DQ<23>
J 0
(-5990 5010);
DISPLAY 0.659574 (-5990 5010);
PAINT MONO (-5990 5010);
DISPLAY INVISIBLE (-5990 5010);
FORCEPROP 1 LASTPIN (-6000 5000) BN 23
J 0
(-6012 5008);
DISPLAY 0.489362 (-6012 5008);
PAINT GREEN (-6012 5008);
FORCEPROP 2 LAST CDS_LIB mstr_standard
J 0
(-5950 5000);
DISPLAY 0.723404 (-5950 5000);
PAINT MONO (-5950 5000);
DISPLAY INVISIBLE (-5950 5000);
FORCEPROP 1 LAST BODY_TYPE PLUMBING
J 0
(-5950 5050);
DISPLAY 0.872340 (-5950 5050);
PAINT GREEN (-5950 5050);
DISPLAY INVISIBLE (-5950 5050);
FORCEPROP 1 LAST HDL_TAP TRUE
J 0
(-5625 4875);
DISPLAY 0.872340 (-5625 4875);
DISPLAY INVISIBLE (-5625 4875);
FORCEPROP 1 LAST PATH I119
J 0
(-5952 5000);
DISPLAY 0.872340 (-5952 5000);
PAINT GREEN (-5952 5000);
DISPLAY INVISIBLE (-5952 5000);
FORCEADD OFFPAGE..1
(-8250 4100);
FORCEPROP 2 LAST $XR0 48 
J 0
(-8501 4100);
DISPLAY 0.638298 (-8501 4100);
PAINT MONO (-8501 4100);
FORCEPROP 2 LAST CDS_LIB mstr_standard
J 0
(-8250 4100);
DISPLAY 0.808511 (-8250 4100);
DISPLAY INVISIBLE (-8250 4100);
FORCEPROP 1 LAST OFFPAGE TRUE
J 0
(-7925 3975);
DISPLAY 0.872340 (-7925 3975);
PAINT GREEN (-7925 3975);
DISPLAY INVISIBLE (-7925 3975);
FORCEPROP 1 LAST COMMENT_BODY TRUE
J 0
(-8125 4000);
DISPLAY 0.872340 (-8125 4000);
PAINT GREEN (-8125 4000);
DISPLAY INVISIBLE (-8125 4000);
FORCEPROP 2 LAST PATH I12
J 0
(-8450 4150);
DISPLAY 1.021277 (-8450 4150);
DISPLAY INVISIBLE (-8450 4150);
FORCEADD TAP..1
(-5950 5300);
FORCEPROP 3 LASTPIN (-6000 5300) SIG_NAME M_L_CPU1_SA_DQ<29>
J 0
(-5990 5310);
DISPLAY 0.659574 (-5990 5310);
PAINT MONO (-5990 5310);
DISPLAY INVISIBLE (-5990 5310);
FORCEPROP 1 LASTPIN (-6000 5300) BN 29
J 0
(-6012 5308);
DISPLAY 0.489362 (-6012 5308);
PAINT GREEN (-6012 5308);
FORCEPROP 2 LAST CDS_LIB mstr_standard
J 0
(-5950 5300);
DISPLAY 0.723404 (-5950 5300);
PAINT MONO (-5950 5300);
DISPLAY INVISIBLE (-5950 5300);
FORCEPROP 1 LAST BODY_TYPE PLUMBING
J 0
(-5950 5350);
DISPLAY 0.872340 (-5950 5350);
PAINT GREEN (-5950 5350);
DISPLAY INVISIBLE (-5950 5350);
FORCEPROP 1 LAST HDL_TAP TRUE
J 0
(-5625 5175);
DISPLAY 0.872340 (-5625 5175);
DISPLAY INVISIBLE (-5625 5175);
FORCEPROP 1 LAST PATH I120
J 0
(-5952 5300);
DISPLAY 0.872340 (-5952 5300);
PAINT GREEN (-5952 5300);
DISPLAY INVISIBLE (-5952 5300);
FORCEADD TAP..1
(-5950 5400);
FORCEPROP 3 LASTPIN (-6000 5400) SIG_NAME M_L_CPU1_SA_DQ<31>
J 0
(-5990 5410);
DISPLAY 0.659574 (-5990 5410);
PAINT MONO (-5990 5410);
DISPLAY INVISIBLE (-5990 5410);
FORCEPROP 1 LASTPIN (-6000 5400) BN 31
J 0
(-6012 5408);
DISPLAY 0.489362 (-6012 5408);
PAINT GREEN (-6012 5408);
FORCEPROP 2 LAST CDS_LIB mstr_standard
J 0
(-5950 5400);
DISPLAY 0.723404 (-5950 5400);
PAINT MONO (-5950 5400);
DISPLAY INVISIBLE (-5950 5400);
FORCEPROP 1 LAST BODY_TYPE PLUMBING
J 0
(-5950 5450);
DISPLAY 0.872340 (-5950 5450);
PAINT GREEN (-5950 5450);
DISPLAY INVISIBLE (-5950 5450);
FORCEPROP 1 LAST HDL_TAP TRUE
J 0
(-5625 5275);
DISPLAY 0.872340 (-5625 5275);
DISPLAY INVISIBLE (-5625 5275);
FORCEPROP 1 LAST PATH I121
J 0
(-5952 5400);
DISPLAY 0.872340 (-5952 5400);
PAINT GREEN (-5952 5400);
DISPLAY INVISIBLE (-5952 5400);
FORCEADD TAP..1
(-5950 5350);
FORCEPROP 3 LASTPIN (-6000 5350) SIG_NAME M_L_CPU1_SA_DQ<30>
J 0
(-5990 5360);
DISPLAY 0.659574 (-5990 5360);
PAINT MONO (-5990 5360);
DISPLAY INVISIBLE (-5990 5360);
FORCEPROP 1 LASTPIN (-6000 5350) BN 30
J 0
(-6012 5358);
DISPLAY 0.489362 (-6012 5358);
PAINT GREEN (-6012 5358);
FORCEPROP 2 LAST CDS_LIB mstr_standard
J 0
(-5950 5350);
DISPLAY 0.723404 (-5950 5350);
PAINT MONO (-5950 5350);
DISPLAY INVISIBLE (-5950 5350);
FORCEPROP 1 LAST BODY_TYPE PLUMBING
J 0
(-5950 5400);
DISPLAY 0.872340 (-5950 5400);
PAINT GREEN (-5950 5400);
DISPLAY INVISIBLE (-5950 5400);
FORCEPROP 1 LAST HDL_TAP TRUE
J 0
(-5625 5225);
DISPLAY 0.872340 (-5625 5225);
DISPLAY INVISIBLE (-5625 5225);
FORCEPROP 1 LAST PATH I122
J 0
(-5952 5350);
DISPLAY 0.872340 (-5952 5350);
PAINT GREEN (-5952 5350);
DISPLAY INVISIBLE (-5952 5350);
FORCEADD TAP..1
(-5950 5250);
FORCEPROP 3 LASTPIN (-6000 5250) SIG_NAME M_L_CPU1_SA_DQ<28>
J 0
(-5990 5260);
DISPLAY 0.659574 (-5990 5260);
PAINT MONO (-5990 5260);
DISPLAY INVISIBLE (-5990 5260);
FORCEPROP 1 LASTPIN (-6000 5250) BN 28
J 0
(-6012 5258);
DISPLAY 0.489362 (-6012 5258);
PAINT GREEN (-6012 5258);
FORCEPROP 2 LAST CDS_LIB mstr_standard
J 0
(-5950 5250);
DISPLAY 0.723404 (-5950 5250);
PAINT MONO (-5950 5250);
DISPLAY INVISIBLE (-5950 5250);
FORCEPROP 1 LAST BODY_TYPE PLUMBING
J 0
(-5950 5300);
DISPLAY 0.872340 (-5950 5300);
PAINT GREEN (-5950 5300);
DISPLAY INVISIBLE (-5950 5300);
FORCEPROP 1 LAST HDL_TAP TRUE
J 0
(-5625 5125);
DISPLAY 0.872340 (-5625 5125);
DISPLAY INVISIBLE (-5625 5125);
FORCEPROP 1 LAST PATH I123
J 0
(-5952 5250);
DISPLAY 0.872340 (-5952 5250);
PAINT GREEN (-5952 5250);
DISPLAY INVISIBLE (-5952 5250);
FORCEADD OFFPAGE..3
(-5275 3800);
FORCEPROP 2 LAST $XR0 48 
J 0
(-5061 3800);
DISPLAY 0.638298 (-5061 3800);
PAINT MONO (-5061 3800);
FORCEPROP 2 LAST CDS_LIB mstr_standard
J 0
(-5275 3800);
DISPLAY 0.723404 (-5275 3800);
PAINT MONO (-5275 3800);
DISPLAY INVISIBLE (-5275 3800);
FORCEPROP 1 LAST OFFPAGE TRUE
J 0
(-4950 3675);
DISPLAY 0.872340 (-4950 3675);
PAINT GREEN (-4950 3675);
DISPLAY INVISIBLE (-4950 3675);
FORCEPROP 1 LAST COMMENT_BODY TRUE
J 0
(-5325 3700);
DISPLAY 0.872340 (-5325 3700);
PAINT GREEN (-5325 3700);
DISPLAY INVISIBLE (-5325 3700);
FORCEPROP 2 LAST PATH I124
J 0
(-5050 3850);
DISPLAY 1.021277 (-5050 3850);
DISPLAY INVISIBLE (-5050 3850);
FORCEADD OFFPAGE..3
(-5275 5450);
FORCEPROP 2 LAST $XR0 48 
J 0
(-5061 5450);
DISPLAY 0.638298 (-5061 5450);
PAINT MONO (-5061 5450);
FORCEPROP 2 LAST CDS_LIB mstr_standard
J 0
(-5275 5450);
DISPLAY 0.723404 (-5275 5450);
PAINT MONO (-5275 5450);
DISPLAY INVISIBLE (-5275 5450);
FORCEPROP 1 LAST OFFPAGE TRUE
J 0
(-4950 5325);
DISPLAY 0.872340 (-4950 5325);
PAINT GREEN (-4950 5325);
DISPLAY INVISIBLE (-4950 5325);
FORCEPROP 1 LAST COMMENT_BODY TRUE
J 0
(-5325 5350);
DISPLAY 0.872340 (-5325 5350);
PAINT GREEN (-5325 5350);
DISPLAY INVISIBLE (-5325 5350);
FORCEPROP 2 LAST PATH I125
J 0
(-5050 5500);
DISPLAY 1.021277 (-5050 5500);
DISPLAY INVISIBLE (-5050 5500);
FORCEADD GND..1
(-6350 900);
FORCEPROP 3 LASTPIN (-6350 950) SIG_NAME GND\g
J 0
(-6340 960);
DISPLAY 0.659574 (-6340 960);
PAINT MONO (-6340 960);
DISPLAY INVISIBLE (-6340 960);
FORCEPROP 1 LAST VOLTAGE 0.0
J 0
(-6395 857);
DISPLAY 0.723404 (-6395 857);
PAINT SKYBLUE (-6395 857);
DISPLAY INVISIBLE (-6395 857);
FORCEPROP 2 LAST CDS_LIB mstr_symbols
J 0
(-6350 900);
DISPLAY 0.808511 (-6350 900);
DISPLAY INVISIBLE (-6350 900);
FORCEPROP 1 LAST SIZE 1B
J 0
(-6275 850);
DISPLAY 0.851064 (-6275 850);
PAINT GREEN (-6275 850);
DISPLAY INVISIBLE (-6275 850);
FORCEPROP 2 LAST BOM_COST MEM
J 0
(-6450 975);
DISPLAY 0.808511 (-6450 975);
DISPLAY INVISIBLE (-6450 975);
FORCEPROP 1 LAST BODY_TYPE PLUMBING
J 0
(-6395 857);
DISPLAY 0.340426 (-6395 857);
PAINT GREEN (-6395 857);
DISPLAY INVISIBLE (-6395 857);
FORCEPROP 1 LAST HDL_POWER GND
J 0
(-6350 1050);
DISPLAY 0.851064 (-6350 1050);
PAINT GREEN (-6350 1050);
DISPLAY INVISIBLE (-6350 1050);
FORCEPROP 1 LAST PATH I126
J 0
(-6275 900);
DISPLAY 0.872340 (-6275 900);
PAINT AQUA (-6275 900);
DISPLAY INVISIBLE (-6275 900);
FORCEADD OFFPAGE..5
(-7125 1300);
FORCEPROP 2 LAST $XR0 109 
J 0
(-7380 1300);
DISPLAY 0.638298 (-7380 1300);
PAINT MONO (-7380 1300);
FORCEPROP 2 LAST CDS_LIB mstr_standard
J 0
(-7125 1300);
DISPLAY 0.808511 (-7125 1300);
DISPLAY INVISIBLE (-7125 1300);
FORCEPROP 2 LAST BOM_COST MEM
J 0
(-7200 1375);
DISPLAY 0.808511 (-7200 1375);
DISPLAY INVISIBLE (-7200 1375);
FORCEPROP 1 LAST OFFPAGE TRUE
J 0
(-6800 1175);
DISPLAY 0.872340 (-6800 1175);
PAINT GREEN (-6800 1175);
DISPLAY INVISIBLE (-6800 1175);
FORCEPROP 1 LAST COMMENT_BODY TRUE
J 0
(-7025 1225);
DISPLAY 0.872340 (-7025 1225);
PAINT GREEN (-7025 1225);
DISPLAY INVISIBLE (-7025 1225);
FORCEPROP 2 LAST PATH I127
J 0
(-7375 1350);
DISPLAY 1.021277 (-7375 1350);
DISPLAY INVISIBLE (-7375 1350);
FORCEADD OFFPAGE..1
(-8250 4150);
FORCEPROP 2 LAST $XR0 48 
J 0
(-8501 4150);
DISPLAY 0.638298 (-8501 4150);
PAINT MONO (-8501 4150);
FORCEPROP 2 LAST CDS_LIB mstr_standard
J 0
(-8250 4150);
DISPLAY 0.723404 (-8250 4150);
PAINT MONO (-8250 4150);
DISPLAY INVISIBLE (-8250 4150);
FORCEPROP 1 LAST OFFPAGE TRUE
J 0
(-7925 4025);
DISPLAY 0.872340 (-7925 4025);
PAINT GREEN (-7925 4025);
DISPLAY INVISIBLE (-7925 4025);
FORCEPROP 1 LAST COMMENT_BODY TRUE
J 0
(-8125 4050);
DISPLAY 0.872340 (-8125 4050);
PAINT GREEN (-8125 4050);
DISPLAY INVISIBLE (-8125 4050);
FORCEPROP 2 LAST PATH I13
J 0
(-8450 4200);
DISPLAY 1.021277 (-8450 4200);
DISPLAY INVISIBLE (-8450 4200);
FORCEADD Q_RES..2
(-6350 1125);
FORCEPROP 1 LAST LOCATION R778
J 0
(-6305 1250);
DISPLAY 0.489362 (-6305 1250);
PAINT SKYBLUE (-6305 1250);
FORCEPROP 0 LAST $SEC 1
J 0
(-6300 1300);
DISPLAY 0.680851 (-6300 1300);
PAINT MONO (-6300 1300);
DISPLAY INVISIBLE (-6300 1300);
FORCEPROP 0 LAST CDS_SEC 1
J 0
(-6300 1300);
DISPLAY 1.021277 (-6300 1300);
DISPLAY INVISIBLE (-6300 1300);
FORCEPROP 1 LASTPIN (-6350 1225) $PN 1
J 0
(-6345 1187);
DISPLAY 0.489362 (-6345 1187);
PAINT MONO (-6345 1187);
FORCEPROP 1 LASTPIN (-6350 1025) $PN 2
J 0
(-6345 1035);
DISPLAY 0.489362 (-6345 1035);
PAINT MONO (-6345 1035);
FORCEPROP 1 LAST PACK_TYPE 0402LF
J 0
(-6310 950);
DISPLAY 0.489362 (-6310 950);
PAINT SKYBLUE (-6310 950);
FORCEPROP 1 LAST VALUE 84.5K
J 0
(-6305 1200);
DISPLAY 0.489362 (-6305 1200);
PAINT SKYBLUE (-6305 1200);
FORCEPROP 1 LAST TOLERANCE 1%
J 0
(-6305 1150);
DISPLAY 0.489362 (-6305 1150);
PAINT SKYBLUE (-6305 1150);
FORCEPROP 1 LAST MATERIAL CHIP
J 0
(-6310 1050);
DISPLAY 0.489362 (-6310 1050);
PAINT SKYBLUE (-6310 1050);
FORCEPROP 1 LAST WATTAGE 1/16W
J 0
(-6310 1100);
DISPLAY 0.489362 (-6310 1100);
PAINT SKYBLUE (-6310 1100);
FORCEPROP 2 LAST CDS_LIB pure_quanta
J 0
(-6350 1125);
DISPLAY INVISIBLE (-6350 1125);
FORCEPROP 1 LAST PATH I136
J 0
(-6300 1300);
DISPLAY 0.978723 (-6300 1300);
PAINT WHITE (-6300 1300);
DISPLAY INVISIBLE (-6300 1300);
FORCEPROP 1 LAST PART_NUMBER CS38452FB05
J 0
(-6310 1000);
DISPLAY 0.489362 (-6310 1000);
PAINT SKYBLUE (-6310 1000);
DISPLAY INVISIBLE (-6310 1000);
FORCEADD GND..1
(-2100 1900);
FORCEPROP 3 LASTPIN (-2100 1950) SIG_NAME GND\g
J 0
(-2090 1960);
DISPLAY 0.659574 (-2090 1960);
PAINT MONO (-2090 1960);
DISPLAY INVISIBLE (-2090 1960);
FORCEPROP 1 LAST VOLTAGE 0.0
J 0
(-2145 1857);
DISPLAY 0.723404 (-2145 1857);
PAINT SKYBLUE (-2145 1857);
DISPLAY INVISIBLE (-2145 1857);
FORCEPROP 1 LAST SIZE 1B
J 0
(-2025 1850);
DISPLAY 0.851064 (-2025 1850);
PAINT GREEN (-2025 1850);
DISPLAY INVISIBLE (-2025 1850);
FORCEPROP 2 LAST CDS_LIB mstr_symbols
J 0
(-2100 1900);
DISPLAY 0.723404 (-2100 1900);
DISPLAY INVISIBLE (-2100 1900);
FORCEPROP 1 LAST BODY_TYPE PLUMBING
J 0
(-2145 1857);
DISPLAY 0.340426 (-2145 1857);
PAINT GREEN (-2145 1857);
DISPLAY INVISIBLE (-2145 1857);
FORCEPROP 1 LAST HDL_POWER GND
J 0
(-2100 2050);
DISPLAY 0.851064 (-2100 2050);
PAINT GREEN (-2100 2050);
DISPLAY INVISIBLE (-2100 2050);
FORCEPROP 1 LAST PATH I137
J 0
(-2025 1900);
DISPLAY 0.872340 (-2025 1900);
PAINT AQUA (-2025 1900);
DISPLAY INVISIBLE (-2025 1900);
FORCEADD SCONN288_DDR506112002KQ..3
(-1200 3675);
FORCEPROP 1 LAST LOCATION J37
J 0
(-1650 5650);
DISPLAY 0.468085 (-1650 5650);
PAINT SKYBLUE (-1650 5650);
FORCEPROP 0 LAST $SEC 3
J 0
(-1650 5800);
DISPLAY 0.680851 (-1650 5800);
PAINT MONO (-1650 5800);
DISPLAY INVISIBLE (-1650 5800);
FORCEPROP 2 LAST CDS_SEC 3
J 0
(-1650 5800);
DISPLAY 1.021277 (-1650 5800);
DISPLAY INVISIBLE (-1650 5800);
FORCEPROP 0 LASTPIN (-600 2075) $PN G1
J 0
(-590 2085);
DISPLAY 0.680851 (-590 2085);
PAINT MONO (-590 2085);
FORCEPROP 0 LASTPIN (-600 2025) $PN G2
J 0
(-590 2035);
DISPLAY 0.680851 (-590 2035);
PAINT MONO (-590 2035);
FORCEPROP 0 LASTPIN (-600 1975) $PN G3
J 0
(-590 1985);
DISPLAY 0.680851 (-590 1985);
PAINT MONO (-590 1985);
FORCEPROP 0 LASTPIN (-1800 5225) $PN 1
J 2
(-1810 5235);
DISPLAY 0.680851 (-1810 5235);
PAINT MONO (-1810 5235);
FORCEPROP 0 LASTPIN (-1800 5275) $PN 145
J 2
(-1810 5285);
DISPLAY 0.680851 (-1810 5285);
PAINT MONO (-1810 5285);
FORCEPROP 0 LASTPIN (-1800 5325) $PN 146
J 2
(-1810 5335);
DISPLAY 0.680851 (-1810 5335);
PAINT MONO (-1810 5335);
FORCEPROP 0 LASTPIN (-600 2175) $PN 6
J 0
(-590 2185);
DISPLAY 0.680851 (-590 2185);
PAINT MONO (-590 2185);
FORCEPROP 0 LASTPIN (-600 2225) $PN 8
J 0
(-590 2235);
DISPLAY 0.680851 (-590 2235);
PAINT MONO (-590 2235);
FORCEPROP 0 LASTPIN (-600 2275) $PN 10
J 0
(-590 2285);
DISPLAY 0.680851 (-590 2285);
PAINT MONO (-590 2285);
FORCEPROP 0 LASTPIN (-600 2325) $PN 13
J 0
(-590 2335);
DISPLAY 0.680851 (-590 2335);
PAINT MONO (-590 2335);
FORCEPROP 0 LASTPIN (-600 2375) $PN 15
J 0
(-590 2385);
DISPLAY 0.680851 (-590 2385);
PAINT MONO (-590 2385);
FORCEPROP 0 LASTPIN (-600 2425) $PN 17
J 0
(-590 2435);
DISPLAY 0.680851 (-590 2435);
PAINT MONO (-590 2435);
FORCEPROP 0 LASTPIN (-600 2475) $PN 19
J 0
(-590 2485);
DISPLAY 0.680851 (-590 2485);
PAINT MONO (-590 2485);
FORCEPROP 0 LASTPIN (-600 2525) $PN 21
J 0
(-590 2535);
DISPLAY 0.680851 (-590 2535);
PAINT MONO (-590 2535);
FORCEPROP 0 LASTPIN (-600 2575) $PN 24
J 0
(-590 2585);
DISPLAY 0.680851 (-590 2585);
PAINT MONO (-590 2585);
FORCEPROP 0 LASTPIN (-600 2625) $PN 26
J 0
(-590 2635);
DISPLAY 0.680851 (-590 2635);
PAINT MONO (-590 2635);
FORCEPROP 0 LASTPIN (-600 2675) $PN 28
J 0
(-590 2685);
DISPLAY 0.680851 (-590 2685);
PAINT MONO (-590 2685);
FORCEPROP 0 LASTPIN (-600 2725) $PN 30
J 0
(-590 2735);
DISPLAY 0.680851 (-590 2735);
PAINT MONO (-590 2735);
FORCEPROP 0 LASTPIN (-600 2775) $PN 32
J 0
(-590 2785);
DISPLAY 0.680851 (-590 2785);
PAINT MONO (-590 2785);
FORCEPROP 0 LASTPIN (-600 2825) $PN 35
J 0
(-590 2835);
DISPLAY 0.680851 (-590 2835);
PAINT MONO (-590 2835);
FORCEPROP 0 LASTPIN (-600 2875) $PN 37
J 0
(-590 2885);
DISPLAY 0.680851 (-590 2885);
PAINT MONO (-590 2885);
FORCEPROP 0 LASTPIN (-600 2925) $PN 39
J 0
(-590 2935);
DISPLAY 0.680851 (-590 2935);
PAINT MONO (-590 2935);
FORCEPROP 0 LASTPIN (-600 2975) $PN 41
J 0
(-590 2985);
DISPLAY 0.680851 (-590 2985);
PAINT MONO (-590 2985);
FORCEPROP 0 LASTPIN (-600 3025) $PN 43
J 0
(-590 3035);
DISPLAY 0.680851 (-590 3035);
PAINT MONO (-590 3035);
FORCEPROP 0 LASTPIN (-600 3075) $PN 46
J 0
(-590 3085);
DISPLAY 0.680851 (-590 3085);
PAINT MONO (-590 3085);
FORCEPROP 0 LASTPIN (-600 3125) $PN 48
J 0
(-590 3135);
DISPLAY 0.680851 (-590 3135);
PAINT MONO (-590 3135);
FORCEPROP 0 LASTPIN (-600 3175) $PN 50
J 0
(-590 3185);
DISPLAY 0.680851 (-590 3185);
PAINT MONO (-590 3185);
FORCEPROP 0 LASTPIN (-600 3225) $PN 52
J 0
(-590 3235);
DISPLAY 0.680851 (-590 3235);
PAINT MONO (-590 3235);
FORCEPROP 0 LASTPIN (-600 3275) $PN 54
J 0
(-590 3285);
DISPLAY 0.680851 (-590 3285);
PAINT MONO (-590 3285);
FORCEPROP 0 LASTPIN (-600 3325) $PN 57
J 0
(-590 3335);
DISPLAY 0.680851 (-590 3335);
PAINT MONO (-590 3335);
FORCEPROP 0 LASTPIN (-600 3375) $PN 59
J 0
(-590 3385);
DISPLAY 0.680851 (-590 3385);
PAINT MONO (-590 3385);
FORCEPROP 0 LASTPIN (-600 3425) $PN 61
J 0
(-590 3435);
DISPLAY 0.680851 (-590 3435);
PAINT MONO (-590 3435);
FORCEPROP 0 LASTPIN (-600 3475) $PN 63
J 0
(-590 3485);
DISPLAY 0.680851 (-590 3485);
PAINT MONO (-590 3485);
FORCEPROP 0 LASTPIN (-600 3525) $PN 65
J 0
(-590 3535);
DISPLAY 0.680851 (-590 3535);
PAINT MONO (-590 3535);
FORCEPROP 0 LASTPIN (-600 3575) $PN 67
J 0
(-590 3585);
DISPLAY 0.680851 (-590 3585);
PAINT MONO (-590 3585);
FORCEPROP 0 LASTPIN (-600 3625) $PN 69
J 0
(-590 3635);
DISPLAY 0.680851 (-590 3635);
PAINT MONO (-590 3635);
FORCEPROP 0 LASTPIN (-600 3675) $PN 71
J 0
(-590 3685);
DISPLAY 0.680851 (-590 3685);
PAINT MONO (-590 3685);
FORCEPROP 0 LASTPIN (-600 3725) $PN 73
J 0
(-590 3735);
DISPLAY 0.680851 (-590 3735);
PAINT MONO (-590 3735);
FORCEPROP 0 LASTPIN (-600 3775) $PN 75
J 0
(-590 3785);
DISPLAY 0.680851 (-590 3785);
PAINT MONO (-590 3785);
FORCEPROP 0 LASTPIN (-600 3825) $PN 77
J 0
(-590 3835);
DISPLAY 0.680851 (-590 3835);
PAINT MONO (-590 3835);
FORCEPROP 0 LASTPIN (-600 3875) $PN 79
J 0
(-590 3885);
DISPLAY 0.680851 (-590 3885);
PAINT MONO (-590 3885);
FORCEPROP 0 LASTPIN (-600 3925) $PN 81
J 0
(-590 3935);
DISPLAY 0.680851 (-590 3935);
PAINT MONO (-590 3935);
FORCEPROP 0 LASTPIN (-600 3975) $PN 83
J 0
(-590 3985);
DISPLAY 0.680851 (-590 3985);
PAINT MONO (-590 3985);
FORCEPROP 0 LASTPIN (-600 4025) $PN 85
J 0
(-590 4035);
DISPLAY 0.680851 (-590 4035);
PAINT MONO (-590 4035);
FORCEPROP 0 LASTPIN (-600 4075) $PN 88
J 0
(-590 4085);
DISPLAY 0.680851 (-590 4085);
PAINT MONO (-590 4085);
FORCEPROP 0 LASTPIN (-600 4125) $PN 90
J 0
(-590 4135);
DISPLAY 0.680851 (-590 4135);
PAINT MONO (-590 4135);
FORCEPROP 0 LASTPIN (-600 4175) $PN 92
J 0
(-590 4185);
DISPLAY 0.680851 (-590 4185);
PAINT MONO (-590 4185);
FORCEPROP 0 LASTPIN (-600 4225) $PN 95
J 0
(-590 4235);
DISPLAY 0.680851 (-590 4235);
PAINT MONO (-590 4235);
FORCEPROP 0 LASTPIN (-600 4275) $PN 97
J 0
(-590 4285);
DISPLAY 0.680851 (-590 4285);
PAINT MONO (-590 4285);
FORCEPROP 0 LASTPIN (-600 4325) $PN 99
J 0
(-590 4335);
DISPLAY 0.680851 (-590 4335);
PAINT MONO (-590 4335);
FORCEPROP 0 LASTPIN (-600 4375) $PN 101
J 0
(-590 4385);
DISPLAY 0.680851 (-590 4385);
PAINT MONO (-590 4385);
FORCEPROP 0 LASTPIN (-600 4425) $PN 103
J 0
(-590 4435);
DISPLAY 0.680851 (-590 4435);
PAINT MONO (-590 4435);
FORCEPROP 0 LASTPIN (-600 4475) $PN 106
J 0
(-590 4485);
DISPLAY 0.680851 (-590 4485);
PAINT MONO (-590 4485);
FORCEPROP 0 LASTPIN (-600 4525) $PN 108
J 0
(-590 4535);
DISPLAY 0.680851 (-590 4535);
PAINT MONO (-590 4535);
FORCEPROP 0 LASTPIN (-600 4575) $PN 110
J 0
(-590 4585);
DISPLAY 0.680851 (-590 4585);
PAINT MONO (-590 4585);
FORCEPROP 0 LASTPIN (-600 4625) $PN 112
J 0
(-590 4635);
DISPLAY 0.680851 (-590 4635);
PAINT MONO (-590 4635);
FORCEPROP 0 LASTPIN (-600 4675) $PN 114
J 0
(-590 4685);
DISPLAY 0.680851 (-590 4685);
PAINT MONO (-590 4685);
FORCEPROP 0 LASTPIN (-600 4725) $PN 117
J 0
(-590 4735);
DISPLAY 0.680851 (-590 4735);
PAINT MONO (-590 4735);
FORCEPROP 0 LASTPIN (-600 4775) $PN 119
J 0
(-590 4785);
DISPLAY 0.680851 (-590 4785);
PAINT MONO (-590 4785);
FORCEPROP 0 LASTPIN (-600 4825) $PN 121
J 0
(-590 4835);
DISPLAY 0.680851 (-590 4835);
PAINT MONO (-590 4835);
FORCEPROP 0 LASTPIN (-600 4875) $PN 123
J 0
(-590 4885);
DISPLAY 0.680851 (-590 4885);
PAINT MONO (-590 4885);
FORCEPROP 0 LASTPIN (-600 4925) $PN 125
J 0
(-590 4935);
DISPLAY 0.680851 (-590 4935);
PAINT MONO (-590 4935);
FORCEPROP 0 LASTPIN (-600 4975) $PN 128
J 0
(-590 4985);
DISPLAY 0.680851 (-590 4985);
PAINT MONO (-590 4985);
FORCEPROP 0 LASTPIN (-600 5025) $PN 130
J 0
(-590 5035);
DISPLAY 0.680851 (-590 5035);
PAINT MONO (-590 5035);
FORCEPROP 0 LASTPIN (-600 5075) $PN 132
J 0
(-590 5085);
DISPLAY 0.680851 (-590 5085);
PAINT MONO (-590 5085);
FORCEPROP 0 LASTPIN (-600 5125) $PN 134
J 0
(-590 5135);
DISPLAY 0.680851 (-590 5135);
PAINT MONO (-590 5135);
FORCEPROP 0 LASTPIN (-600 5175) $PN 136
J 0
(-590 5185);
DISPLAY 0.680851 (-590 5185);
PAINT MONO (-590 5185);
FORCEPROP 0 LASTPIN (-600 5225) $PN 139
J 0
(-590 5235);
DISPLAY 0.680851 (-590 5235);
PAINT MONO (-590 5235);
FORCEPROP 0 LASTPIN (-600 5275) $PN 141
J 0
(-590 5285);
DISPLAY 0.680851 (-590 5285);
PAINT MONO (-590 5285);
FORCEPROP 0 LASTPIN (-600 5325) $PN 143
J 0
(-590 5335);
DISPLAY 0.680851 (-590 5335);
PAINT MONO (-590 5335);
FORCEPROP 0 LASTPIN (-1800 2075) $PN 151
J 2
(-1810 2085);
DISPLAY 0.680851 (-1810 2085);
PAINT MONO (-1810 2085);
FORCEPROP 0 LASTPIN (-1800 2125) $PN 153
J 2
(-1810 2135);
DISPLAY 0.680851 (-1810 2135);
PAINT MONO (-1810 2135);
FORCEPROP 0 LASTPIN (-1800 2175) $PN 155
J 2
(-1810 2185);
DISPLAY 0.680851 (-1810 2185);
PAINT MONO (-1810 2185);
FORCEPROP 0 LASTPIN (-1800 2225) $PN 158
J 2
(-1810 2235);
DISPLAY 0.680851 (-1810 2235);
PAINT MONO (-1810 2235);
FORCEPROP 0 LASTPIN (-1800 2275) $PN 160
J 2
(-1810 2285);
DISPLAY 0.680851 (-1810 2285);
PAINT MONO (-1810 2285);
FORCEPROP 0 LASTPIN (-1800 2325) $PN 162
J 2
(-1810 2335);
DISPLAY 0.680851 (-1810 2335);
PAINT MONO (-1810 2335);
FORCEPROP 0 LASTPIN (-1800 2375) $PN 164
J 2
(-1810 2385);
DISPLAY 0.680851 (-1810 2385);
PAINT MONO (-1810 2385);
FORCEPROP 0 LASTPIN (-1800 2425) $PN 166
J 2
(-1810 2435);
DISPLAY 0.680851 (-1810 2435);
PAINT MONO (-1810 2435);
FORCEPROP 0 LASTPIN (-1800 2475) $PN 169
J 2
(-1810 2485);
DISPLAY 0.680851 (-1810 2485);
PAINT MONO (-1810 2485);
FORCEPROP 0 LASTPIN (-1800 2525) $PN 171
J 2
(-1810 2535);
DISPLAY 0.680851 (-1810 2535);
PAINT MONO (-1810 2535);
FORCEPROP 0 LASTPIN (-1800 2575) $PN 173
J 2
(-1810 2585);
DISPLAY 0.680851 (-1810 2585);
PAINT MONO (-1810 2585);
FORCEPROP 0 LASTPIN (-1800 2625) $PN 175
J 2
(-1810 2635);
DISPLAY 0.680851 (-1810 2635);
PAINT MONO (-1810 2635);
FORCEPROP 0 LASTPIN (-1800 2675) $PN 177
J 2
(-1810 2685);
DISPLAY 0.680851 (-1810 2685);
PAINT MONO (-1810 2685);
FORCEPROP 0 LASTPIN (-1800 2725) $PN 180
J 2
(-1810 2735);
DISPLAY 0.680851 (-1810 2735);
PAINT MONO (-1810 2735);
FORCEPROP 0 LASTPIN (-1800 2775) $PN 182
J 2
(-1810 2785);
DISPLAY 0.680851 (-1810 2785);
PAINT MONO (-1810 2785);
FORCEPROP 0 LASTPIN (-1800 2825) $PN 184
J 2
(-1810 2835);
DISPLAY 0.680851 (-1810 2835);
PAINT MONO (-1810 2835);
FORCEPROP 0 LASTPIN (-1800 2875) $PN 186
J 2
(-1810 2885);
DISPLAY 0.680851 (-1810 2885);
PAINT MONO (-1810 2885);
FORCEPROP 0 LASTPIN (-1800 2925) $PN 188
J 2
(-1810 2935);
DISPLAY 0.680851 (-1810 2935);
PAINT MONO (-1810 2935);
FORCEPROP 0 LASTPIN (-1800 2975) $PN 191
J 2
(-1810 2985);
DISPLAY 0.680851 (-1810 2985);
PAINT MONO (-1810 2985);
FORCEPROP 0 LASTPIN (-1800 3025) $PN 193
J 2
(-1810 3035);
DISPLAY 0.680851 (-1810 3035);
PAINT MONO (-1810 3035);
FORCEPROP 0 LASTPIN (-1800 3075) $PN 195
J 2
(-1810 3085);
DISPLAY 0.680851 (-1810 3085);
PAINT MONO (-1810 3085);
FORCEPROP 0 LASTPIN (-1800 3125) $PN 197
J 2
(-1810 3135);
DISPLAY 0.680851 (-1810 3135);
PAINT MONO (-1810 3135);
FORCEPROP 0 LASTPIN (-1800 3175) $PN 199
J 2
(-1810 3185);
DISPLAY 0.680851 (-1810 3185);
PAINT MONO (-1810 3185);
FORCEPROP 0 LASTPIN (-1800 3225) $PN 202
J 2
(-1810 3235);
DISPLAY 0.680851 (-1810 3235);
PAINT MONO (-1810 3235);
FORCEPROP 0 LASTPIN (-1800 3275) $PN 204
J 2
(-1810 3285);
DISPLAY 0.680851 (-1810 3285);
PAINT MONO (-1810 3285);
FORCEPROP 0 LASTPIN (-1800 3325) $PN 206
J 2
(-1810 3335);
DISPLAY 0.680851 (-1810 3335);
PAINT MONO (-1810 3335);
FORCEPROP 0 LASTPIN (-1800 3375) $PN 208
J 2
(-1810 3385);
DISPLAY 0.680851 (-1810 3385);
PAINT MONO (-1810 3385);
FORCEPROP 0 LASTPIN (-1800 3425) $PN 210
J 2
(-1810 3435);
DISPLAY 0.680851 (-1810 3435);
PAINT MONO (-1810 3435);
FORCEPROP 0 LASTPIN (-1800 3475) $PN 212
J 2
(-1810 3485);
DISPLAY 0.680851 (-1810 3485);
PAINT MONO (-1810 3485);
FORCEPROP 0 LASTPIN (-1800 3525) $PN 214
J 2
(-1810 3535);
DISPLAY 0.680851 (-1810 3535);
PAINT MONO (-1810 3535);
FORCEPROP 0 LASTPIN (-1800 3575) $PN 216
J 2
(-1810 3585);
DISPLAY 0.680851 (-1810 3585);
PAINT MONO (-1810 3585);
FORCEPROP 0 LASTPIN (-1800 3625) $PN 219
J 2
(-1810 3635);
DISPLAY 0.680851 (-1810 3635);
PAINT MONO (-1810 3635);
FORCEPROP 0 LASTPIN (-1800 3675) $PN 222
J 2
(-1810 3685);
DISPLAY 0.680851 (-1810 3685);
PAINT MONO (-1810 3685);
FORCEPROP 0 LASTPIN (-1800 3725) $PN 224
J 2
(-1810 3735);
DISPLAY 0.680851 (-1810 3735);
PAINT MONO (-1810 3735);
FORCEPROP 0 LASTPIN (-1800 3775) $PN 226
J 2
(-1810 3785);
DISPLAY 0.680851 (-1810 3785);
PAINT MONO (-1810 3785);
FORCEPROP 0 LASTPIN (-1800 3825) $PN 228
J 2
(-1810 3835);
DISPLAY 0.680851 (-1810 3835);
PAINT MONO (-1810 3835);
FORCEPROP 0 LASTPIN (-1800 3875) $PN 230
J 2
(-1810 3885);
DISPLAY 0.680851 (-1810 3885);
PAINT MONO (-1810 3885);
FORCEPROP 0 LASTPIN (-1800 3925) $PN 233
J 2
(-1810 3935);
DISPLAY 0.680851 (-1810 3935);
PAINT MONO (-1810 3935);
FORCEPROP 0 LASTPIN (-1800 3975) $PN 235
J 2
(-1810 3985);
DISPLAY 0.680851 (-1810 3985);
PAINT MONO (-1810 3985);
FORCEPROP 0 LASTPIN (-1800 4025) $PN 237
J 2
(-1810 4035);
DISPLAY 0.680851 (-1810 4035);
PAINT MONO (-1810 4035);
FORCEPROP 0 LASTPIN (-1800 4075) $PN 240
J 2
(-1810 4085);
DISPLAY 0.680851 (-1810 4085);
PAINT MONO (-1810 4085);
FORCEPROP 0 LASTPIN (-1800 4125) $PN 242
J 2
(-1810 4135);
DISPLAY 0.680851 (-1810 4135);
PAINT MONO (-1810 4135);
FORCEPROP 0 LASTPIN (-1800 4175) $PN 244
J 2
(-1810 4185);
DISPLAY 0.680851 (-1810 4185);
PAINT MONO (-1810 4185);
FORCEPROP 0 LASTPIN (-1800 4225) $PN 246
J 2
(-1810 4235);
DISPLAY 0.680851 (-1810 4235);
PAINT MONO (-1810 4235);
FORCEPROP 0 LASTPIN (-1800 4275) $PN 248
J 2
(-1810 4285);
DISPLAY 0.680851 (-1810 4285);
PAINT MONO (-1810 4285);
FORCEPROP 0 LASTPIN (-1800 4325) $PN 251
J 2
(-1810 4335);
DISPLAY 0.680851 (-1810 4335);
PAINT MONO (-1810 4335);
FORCEPROP 0 LASTPIN (-1800 4375) $PN 253
J 2
(-1810 4385);
DISPLAY 0.680851 (-1810 4385);
PAINT MONO (-1810 4385);
FORCEPROP 0 LASTPIN (-1800 4425) $PN 255
J 2
(-1810 4435);
DISPLAY 0.680851 (-1810 4435);
PAINT MONO (-1810 4435);
FORCEPROP 0 LASTPIN (-1800 4475) $PN 257
J 2
(-1810 4485);
DISPLAY 0.680851 (-1810 4485);
PAINT MONO (-1810 4485);
FORCEPROP 0 LASTPIN (-1800 4525) $PN 259
J 2
(-1810 4535);
DISPLAY 0.680851 (-1810 4535);
PAINT MONO (-1810 4535);
FORCEPROP 0 LASTPIN (-1800 4575) $PN 262
J 2
(-1810 4585);
DISPLAY 0.680851 (-1810 4585);
PAINT MONO (-1810 4585);
FORCEPROP 0 LASTPIN (-1800 4625) $PN 264
J 2
(-1810 4635);
DISPLAY 0.680851 (-1810 4635);
PAINT MONO (-1810 4635);
FORCEPROP 0 LASTPIN (-1800 4675) $PN 266
J 2
(-1810 4685);
DISPLAY 0.680851 (-1810 4685);
PAINT MONO (-1810 4685);
FORCEPROP 0 LASTPIN (-1800 4725) $PN 268
J 2
(-1810 4735);
DISPLAY 0.680851 (-1810 4735);
PAINT MONO (-1810 4735);
FORCEPROP 0 LASTPIN (-1800 4775) $PN 270
J 2
(-1810 4785);
DISPLAY 0.680851 (-1810 4785);
PAINT MONO (-1810 4785);
FORCEPROP 0 LASTPIN (-1800 4825) $PN 273
J 2
(-1810 4835);
DISPLAY 0.680851 (-1810 4835);
PAINT MONO (-1810 4835);
FORCEPROP 0 LASTPIN (-1800 4875) $PN 275
J 2
(-1810 4885);
DISPLAY 0.680851 (-1810 4885);
PAINT MONO (-1810 4885);
FORCEPROP 0 LASTPIN (-1800 4925) $PN 277
J 2
(-1810 4935);
DISPLAY 0.680851 (-1810 4935);
PAINT MONO (-1810 4935);
FORCEPROP 0 LASTPIN (-1800 4975) $PN 279
J 2
(-1810 4985);
DISPLAY 0.680851 (-1810 4985);
PAINT MONO (-1810 4985);
FORCEPROP 0 LASTPIN (-1800 5025) $PN 281
J 2
(-1810 5035);
DISPLAY 0.680851 (-1810 5035);
PAINT MONO (-1810 5035);
FORCEPROP 0 LASTPIN (-1800 5075) $PN 284
J 2
(-1810 5085);
DISPLAY 0.680851 (-1810 5085);
PAINT MONO (-1810 5085);
FORCEPROP 0 LASTPIN (-1800 5125) $PN 286
J 2
(-1810 5135);
DISPLAY 0.680851 (-1810 5135);
PAINT MONO (-1810 5135);
FORCEPROP 0 LASTPIN (-1800 5175) $PN 288
J 2
(-1810 5185);
DISPLAY 0.680851 (-1810 5185);
PAINT MONO (-1810 5185);
FORCEPROP 1 LAST MATERIAL IO
J 0
(-1650 5500);
DISPLAY 0.468085 (-1650 5500);
PAINT SKYBLUE (-1650 5500);
FORCEPROP 2 LAST PART_TYPE SMLF
J 0
(-1650 5750);
DISPLAY 1.021277 (-1650 5750);
FORCEPROP 2 LAST VALUE SCONN288_DDR506112002KQ
J 0
(-1650 5700);
DISPLAY 0.489362 (-1650 5700);
PAINT SKYBLUE (-1650 5700);
FORCEPROP 2 LAST CDS_LIB pure_quanta
J 0
(-1200 3675);
DISPLAY INVISIBLE (-1200 3675);
FORCEPROP 1 LAST NEEDS_NO_SIZE TRUE
J 0
(-1200 3675);
DISPLAY 0.723404 (-1200 3675);
PAINT GREEN (-1200 3675);
DISPLAY INVISIBLE (-1200 3675);
FORCEPROP 1 LAST CDS_LMAN_SYM_OUTLINE -450,1800,450,-1750
J 0
(-1200 3675);
DISPLAY 0.468085 (-1200 3675);
PAINT GREEN (-1200 3675);
DISPLAY INVISIBLE (-1200 3675);
FORCEPROP 1 LAST PATH I138
J 0
(-1200 3675);
DISPLAY 0.723404 (-1200 3675);
PAINT GREEN (-1200 3675);
DISPLAY INVISIBLE (-1200 3675);
FORCEPROP 1 LAST PART_NUMBER DFHST8FS479
J 0
(-1650 5575);
DISPLAY 0.468085 (-1650 5575);
PAINT SKYBLUE (-1650 5575);
DISPLAY INVISIBLE (-1650 5575);
FORCEADD GND..1
(-300 1675);
FORCEPROP 3 LASTPIN (-300 1725) SIG_NAME GND\g
J 0
(-290 1735);
DISPLAY 0.659574 (-290 1735);
PAINT MONO (-290 1735);
DISPLAY INVISIBLE (-290 1735);
FORCEPROP 1 LAST VOLTAGE 0.0
J 0
(-345 1632);
DISPLAY 0.723404 (-345 1632);
PAINT SKYBLUE (-345 1632);
DISPLAY INVISIBLE (-345 1632);
FORCEPROP 2 LAST CDS_LIB mstr_symbols
J 0
(-300 1675);
DISPLAY 0.723404 (-300 1675);
DISPLAY INVISIBLE (-300 1675);
FORCEPROP 1 LAST SIZE 1B
J 0
(-225 1625);
DISPLAY 0.851064 (-225 1625);
PAINT GREEN (-225 1625);
DISPLAY INVISIBLE (-225 1625);
FORCEPROP 1 LAST BODY_TYPE PLUMBING
J 0
(-345 1632);
DISPLAY 0.340426 (-345 1632);
PAINT GREEN (-345 1632);
DISPLAY INVISIBLE (-345 1632);
FORCEPROP 1 LAST HDL_POWER GND
J 0
(-300 1825);
DISPLAY 0.851064 (-300 1825);
PAINT GREEN (-300 1825);
DISPLAY INVISIBLE (-300 1825);
FORCEPROP 1 LAST PATH I139
J 0
(-225 1675);
DISPLAY 0.872340 (-225 1675);
PAINT AQUA (-225 1675);
DISPLAY INVISIBLE (-225 1675);
FORCEADD OFFPAGE..1
(-8250 4400);
FORCEPROP 2 LAST $XR0 48 
J 0
(-8501 4400);
DISPLAY 0.638298 (-8501 4400);
PAINT MONO (-8501 4400);
FORCEPROP 2 LAST CDS_LIB mstr_standard
J 0
(-8250 4400);
DISPLAY 0.808511 (-8250 4400);
DISPLAY INVISIBLE (-8250 4400);
FORCEPROP 1 LAST OFFPAGE TRUE
J 0
(-7925 4275);
DISPLAY 0.872340 (-7925 4275);
PAINT GREEN (-7925 4275);
DISPLAY INVISIBLE (-7925 4275);
FORCEPROP 1 LAST COMMENT_BODY TRUE
J 0
(-8125 4300);
DISPLAY 0.872340 (-8125 4300);
PAINT GREEN (-8125 4300);
DISPLAY INVISIBLE (-8125 4300);
FORCEPROP 2 LAST PATH I14
J 0
(-8450 4450);
DISPLAY 1.021277 (-8450 4450);
DISPLAY INVISIBLE (-8450 4450);
FORCEADD OFFPAGE..1
(-8250 4300);
FORCEPROP 2 LAST $XR0 48 
J 0
(-8501 4300);
DISPLAY 0.638298 (-8501 4300);
PAINT MONO (-8501 4300);
FORCEPROP 2 LAST CDS_LIB mstr_standard
J 0
(-8250 4300);
DISPLAY 0.723404 (-8250 4300);
PAINT MONO (-8250 4300);
DISPLAY INVISIBLE (-8250 4300);
FORCEPROP 1 LAST OFFPAGE TRUE
J 0
(-7925 4175);
DISPLAY 0.872340 (-7925 4175);
PAINT GREEN (-7925 4175);
DISPLAY INVISIBLE (-7925 4175);
FORCEPROP 1 LAST COMMENT_BODY TRUE
J 0
(-8125 4200);
DISPLAY 0.872340 (-8125 4200);
PAINT GREEN (-8125 4200);
DISPLAY INVISIBLE (-8125 4200);
FORCEPROP 2 LAST PATH I15
J 0
(-8450 4350);
DISPLAY 1.021277 (-8450 4350);
DISPLAY INVISIBLE (-8450 4350);
FORCEADD OFFPAGE..1
(-8250 4250);
FORCEPROP 2 LAST $XR0 48 
J 0
(-8501 4250);
DISPLAY 0.638298 (-8501 4250);
PAINT MONO (-8501 4250);
FORCEPROP 2 LAST CDS_LIB mstr_standard
J 0
(-8250 4250);
DISPLAY 0.808511 (-8250 4250);
DISPLAY INVISIBLE (-8250 4250);
FORCEPROP 1 LAST OFFPAGE TRUE
J 0
(-7925 4125);
DISPLAY 0.872340 (-7925 4125);
PAINT GREEN (-7925 4125);
DISPLAY INVISIBLE (-7925 4125);
FORCEPROP 1 LAST COMMENT_BODY TRUE
J 0
(-8125 4150);
DISPLAY 0.872340 (-8125 4150);
PAINT GREEN (-8125 4150);
DISPLAY INVISIBLE (-8125 4150);
FORCEPROP 2 LAST PATH I16
J 0
(-8450 4300);
DISPLAY 1.021277 (-8450 4300);
DISPLAY INVISIBLE (-8450 4300);
FORCEADD OFFPAGE..1
(-8250 4450);
FORCEPROP 2 LAST $XR0 48 
J 0
(-8501 4450);
DISPLAY 0.638298 (-8501 4450);
PAINT MONO (-8501 4450);
FORCEPROP 2 LAST CDS_LIB mstr_standard
J 0
(-8250 4450);
DISPLAY 0.723404 (-8250 4450);
PAINT MONO (-8250 4450);
DISPLAY INVISIBLE (-8250 4450);
FORCEPROP 1 LAST OFFPAGE TRUE
J 0
(-7925 4325);
DISPLAY 0.872340 (-7925 4325);
PAINT GREEN (-7925 4325);
DISPLAY INVISIBLE (-7925 4325);
FORCEPROP 1 LAST COMMENT_BODY TRUE
J 0
(-8125 4350);
DISPLAY 0.872340 (-8125 4350);
PAINT GREEN (-8125 4350);
DISPLAY INVISIBLE (-8125 4350);
FORCEPROP 2 LAST PATH I17
J 0
(-8450 4500);
DISPLAY 1.021277 (-8450 4500);
DISPLAY INVISIBLE (-8450 4500);
FORCEADD OFFPAGE..1
(-8250 4550);
FORCEPROP 2 LAST $XR0 48 
J 0
(-8501 4550);
DISPLAY 0.638298 (-8501 4550);
PAINT MONO (-8501 4550);
FORCEPROP 2 LAST CDS_LIB mstr_standard
J 0
(-8250 4550);
DISPLAY 0.808511 (-8250 4550);
DISPLAY INVISIBLE (-8250 4550);
FORCEPROP 1 LAST OFFPAGE TRUE
J 0
(-7925 4425);
DISPLAY 0.872340 (-7925 4425);
PAINT GREEN (-7925 4425);
DISPLAY INVISIBLE (-7925 4425);
FORCEPROP 1 LAST COMMENT_BODY TRUE
J 0
(-8125 4450);
DISPLAY 0.872340 (-8125 4450);
PAINT GREEN (-8125 4450);
DISPLAY INVISIBLE (-8125 4450);
FORCEPROP 2 LAST PATH I18
J 0
(-8450 4600);
DISPLAY 1.021277 (-8450 4600);
DISPLAY INVISIBLE (-8450 4600);
FORCEADD Q_CAP..1
R 2
(-8575 3225);
FORCEPROP 1 LAST LOCATION C180
J 2
(-8625 3325);
DISPLAY 0.489362 (-8625 3325);
PAINT SKYBLUE (-8625 3325);
FORCEPROP 0 LAST $SEC 1
J 0
(-8625 3375);
DISPLAY 0.680851 (-8625 3375);
PAINT MONO (-8625 3375);
DISPLAY INVISIBLE (-8625 3375);
FORCEPROP 0 LAST CDS_SEC 1
J 0
(-8625 3375);
DISPLAY 1.021277 (-8625 3375);
DISPLAY INVISIBLE (-8625 3375);
FORCEPROP 1 LASTPIN (-8575 3325) $PN 1
J 2
(-8585 3305);
DISPLAY 0.489362 (-8585 3305);
PAINT MONO (-8585 3305);
FORCEPROP 1 LASTPIN (-8575 3125) $PN 2
J 2
(-8585 3105);
DISPLAY 0.489362 (-8585 3105);
PAINT MONO (-8585 3105);
FORCEPROP 1 LAST MATERIAL X7R
J 2
(-8625 3125);
DISPLAY 0.489362 (-8625 3125);
PAINT SKYBLUE (-8625 3125);
FORCEPROP 1 LAST TOLERANCE 10%
J 2
(-8625 3175);
DISPLAY 0.489362 (-8625 3175);
PAINT SKYBLUE (-8625 3175);
FORCEPROP 1 LAST VOLTAGE 25V
J 2
(-8625 3225);
DISPLAY 0.489362 (-8625 3225);
PAINT SKYBLUE (-8625 3225);
FORCEPROP 1 LAST PACK_TYPE 0402
J 2
(-8625 3025);
DISPLAY 0.489362 (-8625 3025);
PAINT SKYBLUE (-8625 3025);
FORCEPROP 1 LAST VALUE 0.1UF
J 2
(-8625 3275);
DISPLAY 0.489362 (-8625 3275);
PAINT SKYBLUE (-8625 3275);
FORCEPROP 0 LAST BOM_COST MEM
J 2
(-8630 3370);
DISPLAY 0.595745 (-8630 3370);
PAINT MONO (-8630 3370);
DISPLAY INVISIBLE (-8630 3370);
FORCEPROP 2 LAST CDS_LIB pure_quanta
J 0
(-8575 3225);
DISPLAY INVISIBLE (-8575 3225);
FORCEPROP 2 LAST ROOM 
J 2
(-8630 3370);
DISPLAY 0.595745 (-8630 3370);
PAINT RED (-8630 3370);
DISPLAY INVISIBLE (-8630 3370);
FORCEPROP 1 LAST PATH I185
J 2
(-8625 3375);
DISPLAY 0.978723 (-8625 3375);
PAINT WHITE (-8625 3375);
DISPLAY INVISIBLE (-8625 3375);
FORCEPROP 1 LAST PART_NUMBER CH4104K1B00
J 2
(-8625 3075);
DISPLAY 0.489362 (-8625 3075);
PAINT SKYBLUE (-8625 3075);
DISPLAY INVISIBLE (-8625 3075);
FORCEADD GND..1
(-8575 3000);
FORCEPROP 3 LASTPIN (-8575 3050) SIG_NAME GND\g
J 0
(-8565 3060);
DISPLAY 0.659574 (-8565 3060);
PAINT MONO (-8565 3060);
DISPLAY INVISIBLE (-8565 3060);
FORCEPROP 2 LAST ROOM MEM_EFGH_DECOUPLING_CAPS
J 0
(-8550 3075);
DISPLAY 0.659574 (-8550 3075);
PAINT RED (-8550 3075);
DISPLAY INVISIBLE (-8550 3075);
FORCEPROP 1 LAST VOLTAGE 0
J 0
(-8595 3095);
DISPLAY 0.829787 (-8595 3095);
PAINT SKYBLUE (-8595 3095);
DISPLAY INVISIBLE (-8595 3095);
FORCEPROP 2 LAST CDS_LIB mstr_symbols
J 0
(-8575 3000);
DISPLAY 0.808511 (-8575 3000);
DISPLAY INVISIBLE (-8575 3000);
FORCEPROP 1 LAST SIZE 1B
J 0
(-8500 2950);
DISPLAY 0.723404 (-8500 2950);
PAINT GREEN (-8500 2950);
DISPLAY INVISIBLE (-8500 2950);
FORCEPROP 2 LAST BOM_COST MEM
J 0
(-8550 3125);
DISPLAY 0.659574 (-8550 3125);
DISPLAY INVISIBLE (-8550 3125);
FORCEPROP 1 LAST BODY_TYPE PLUMBING
J 0
(-8620 2957);
DISPLAY 0.276596 (-8620 2957);
PAINT GREEN (-8620 2957);
DISPLAY INVISIBLE (-8620 2957);
FORCEPROP 1 LAST HDL_POWER GND
J 0
(-8575 3150);
DISPLAY 0.723404 (-8575 3150);
PAINT GREEN (-8575 3150);
DISPLAY INVISIBLE (-8575 3150);
FORCEPROP 1 LAST PATH I186
J 0
(-8500 3000);
DISPLAY 0.872340 (-8500 3000);
PAINT AQUA (-8500 3000);
DISPLAY INVISIBLE (-8500 3000);
FORCEADD OFFPAGE..6
(-9000 2150);
FORCEPROP 2 LAST $XR4 108 
J 0
(-9280 2222);
DISPLAY 0.638298 (-9280 2222);
PAINT MONO (-9280 2222);
FORCEPROP 2 LAST $XR3 107 
J 0
(-9280 2078);
DISPLAY 0.638298 (-9280 2078);
PAINT MONO (-9280 2078);
FORCEPROP 2 LAST $XR2 106 
J 0
(-9280 2186);
DISPLAY 0.638298 (-9280 2186);
PAINT MONO (-9280 2186);
FORCEPROP 2 LAST $XR1 105 
J 0
(-9280 2114);
DISPLAY 0.638298 (-9280 2114);
PAINT MONO (-9280 2114);
FORCEPROP 2 LAST $XR0 104 
J 0
(-9280 2150);
DISPLAY 0.638298 (-9280 2150);
PAINT MONO (-9280 2150);
FORCEPROP 2 LAST CDS_LIB mstr_standard
J 0
(-9000 2150);
DISPLAY INVISIBLE (-9000 2150);
FORCEPROP 1 LAST OFFPAGE TRUE
J 0
(-8675 2025);
DISPLAY 0.872340 (-8675 2025);
PAINT GREEN (-8675 2025);
DISPLAY INVISIBLE (-8675 2025);
FORCEPROP 1 LAST COMMENT_BODY TRUE
J 0
(-8900 2075);
DISPLAY 0.872340 (-8900 2075);
PAINT GREEN (-8900 2075);
DISPLAY INVISIBLE (-8900 2075);
FORCEPROP 2 LAST PATH I187
J 0
(-8950 2225);
DISPLAY 1.021277 (-8950 2225);
DISPLAY INVISIBLE (-8950 2225);
FORCEADD Q_RES..1
R 2
(-8450 2150);
FORCEPROP 1 LAST LOCATION R314
J 2
(-8400 2200);
DISPLAY 0.489362 (-8400 2200);
PAINT SKYBLUE (-8400 2200);
FORCEPROP 0 LAST $SEC 1
J 0
(-8400 2250);
DISPLAY 0.680851 (-8400 2250);
PAINT MONO (-8400 2250);
DISPLAY INVISIBLE (-8400 2250);
FORCEPROP 0 LAST CDS_SEC 1
J 0
(-8400 2250);
DISPLAY 1.021277 (-8400 2250);
DISPLAY INVISIBLE (-8400 2250);
FORCEPROP 1 LASTPIN (-8350 2150) $PN 1
J 2
(-8362 2162);
DISPLAY 0.489362 (-8362 2162);
PAINT MONO (-8362 2162);
FORCEPROP 1 LASTPIN (-8550 2150) $PN 2
J 2
(-8512 2162);
DISPLAY 0.489362 (-8512 2162);
PAINT MONO (-8512 2162);
FORCEPROP 1 LAST VALUE 1K
J 0
(-8450 2100);
DISPLAY 0.489362 (-8450 2100);
PAINT SKYBLUE (-8450 2100);
FORCEPROP 1 LAST PACK_TYPE 0402LF
J 0
(-8625 2075);
DISPLAY 0.489362 (-8625 2075);
PAINT SKYBLUE (-8625 2075);
DISPLAY INVISIBLE (-8625 2075);
FORCEPROP 1 LAST MATERIAL CHIP
J 0
(-8625 2125);
DISPLAY 0.489362 (-8625 2125);
PAINT SKYBLUE (-8625 2125);
DISPLAY INVISIBLE (-8625 2125);
FORCEPROP 1 LAST WATTAGE 1/16W
J 0
(-8375 2075);
DISPLAY 0.489362 (-8375 2075);
PAINT SKYBLUE (-8375 2075);
DISPLAY INVISIBLE (-8375 2075);
FORCEPROP 2 LAST CDS_LIB pure_quanta
J 0
(-8450 2150);
DISPLAY INVISIBLE (-8450 2150);
FORCEPROP 2 LAST BOM_COST MEM
J 0
(-8475 2300);
DISPLAY 0.744681 (-8475 2300);
PAINT WHITE (-8475 2300);
DISPLAY INVISIBLE (-8475 2300);
FORCEPROP 1 LAST TOLERANCE 1%
J 2
(-8325 2125);
DISPLAY 0.489362 (-8325 2125);
PAINT SKYBLUE (-8325 2125);
DISPLAY INVISIBLE (-8325 2125);
FORCEPROP 2 LAST ROOM 
J 0
(-8475 2250);
DISPLAY 0.744681 (-8475 2250);
PAINT RED (-8475 2250);
DISPLAY INVISIBLE (-8475 2250);
FORCEPROP 1 LAST PATH I188
J 2
(-8400 2300);
DISPLAY 0.978723 (-8400 2300);
PAINT WHITE (-8400 2300);
DISPLAY INVISIBLE (-8400 2300);
FORCEPROP 1 LAST PART_NUMBER CS21002FB06
J 0
(-8550 2200);
DISPLAY 0.489362 (-8550 2200);
PAINT SKYBLUE (-8550 2200);
DISPLAY INVISIBLE (-8550 2200);
FORCEADD VCC_CORE..1
(-8325 2475);
FORCEPROP 3 LASTPIN (-8325 2425) SIG_NAME P3V3\g
J 0
(-8315 2435);
DISPLAY 0.659574 (-8315 2435);
PAINT MONO (-8315 2435);
DISPLAY INVISIBLE (-8315 2435);
FORCEPROP 1 LAST HDL_POWER P3V3
J 1
(-8325 2525);
DISPLAY 0.489362 (-8325 2525);
PAINT GREEN (-8325 2525);
FORCEPROP 2 LAST ROOM PVCCINFAON_CPU0_CTRL
J 0
(-8325 2575);
DISPLAY 0.808511 (-8325 2575);
PAINT RED (-8325 2575);
DISPLAY INVISIBLE (-8325 2575);
FORCEPROP 0 LAST VOLTAGE 3.3
J 0
(-8600 2625);
DISPLAY 1.021277 (-8600 2625);
PAINT SKYBLUE (-8600 2625);
DISPLAY INVISIBLE (-8600 2625);
FORCEPROP 2 LAST CDS_LIB mstr_symbols
J 0
(-8325 2475);
DISPLAY INVISIBLE (-8325 2475);
FORCEPROP 1 LAST PATH I189
J 0
(-8275 2500);
DISPLAY 0.872340 (-8275 2500);
PAINT AQUA (-8275 2500);
DISPLAY INVISIBLE (-8275 2500);
FORCEADD OFFPAGE..1
(-8250 4600);
FORCEPROP 2 LAST $XR0 48 
J 0
(-8501 4600);
DISPLAY 0.638298 (-8501 4600);
PAINT MONO (-8501 4600);
FORCEPROP 2 LAST CDS_LIB mstr_standard
J 0
(-8250 4600);
DISPLAY 0.723404 (-8250 4600);
PAINT MONO (-8250 4600);
DISPLAY INVISIBLE (-8250 4600);
FORCEPROP 1 LAST OFFPAGE TRUE
J 0
(-7925 4475);
DISPLAY 0.872340 (-7925 4475);
PAINT GREEN (-7925 4475);
DISPLAY INVISIBLE (-7925 4475);
FORCEPROP 1 LAST COMMENT_BODY TRUE
J 0
(-8125 4500);
DISPLAY 0.872340 (-8125 4500);
PAINT GREEN (-8125 4500);
DISPLAY INVISIBLE (-8125 4500);
FORCEPROP 2 LAST PATH I19
J 0
(-8450 4650);
DISPLAY 1.021277 (-8450 4650);
DISPLAY INVISIBLE (-8450 4650);
FORCEADD Q_RES..2
(-8325 2300);
FORCEPROP 1 LAST LOCATION R115
J 0
(-8280 2425);
DISPLAY 0.489362 (-8280 2425);
PAINT SKYBLUE (-8280 2425);
FORCEPROP 0 LAST $SEC 1
J 0
(-8275 2475);
DISPLAY 0.680851 (-8275 2475);
PAINT MONO (-8275 2475);
DISPLAY INVISIBLE (-8275 2475);
FORCEPROP 0 LAST CDS_SEC 1
J 0
(-8275 2475);
DISPLAY 1.021277 (-8275 2475);
DISPLAY INVISIBLE (-8275 2475);
FORCEPROP 1 LASTPIN (-8325 2400) $PN 1
J 0
(-8320 2362);
DISPLAY 0.489362 (-8320 2362);
PAINT MONO (-8320 2362);
FORCEPROP 1 LASTPIN (-8325 2200) $PN 2
J 0
(-8320 2210);
DISPLAY 0.489362 (-8320 2210);
PAINT MONO (-8320 2210);
FORCEPROP 1 LAST PACK_TYPE 0402LF
J 0
(-8275 2250);
DISPLAY 0.489362 (-8275 2250);
PAINT SKYBLUE (-8275 2250);
FORCEPROP 1 LAST VALUE 1K
J 0
(-8280 2375);
DISPLAY 0.489362 (-8280 2375);
PAINT SKYBLUE (-8280 2375);
FORCEPROP 1 LAST MATERIAL EMPTY
J 0
(-8275 2300);
DISPLAY 0.489362 (-8275 2300);
PAINT RED (-8275 2300);
FORCEPROP 1 LAST WATTAGE 1/16W
J 0
(-8275 2325);
DISPLAY 0.489362 (-8275 2325);
PAINT SKYBLUE (-8275 2325);
FORCEPROP 1 LAST TOLERANCE 1%
J 0
(-8275 2350);
DISPLAY 0.489362 (-8275 2350);
PAINT SKYBLUE (-8275 2350);
FORCEPROP 2 LAST CDS_LIB pure_quanta
J 0
(-8325 2300);
DISPLAY INVISIBLE (-8325 2300);
FORCEPROP 2 LAST BOM_COST MEM
J 0
(-8275 2475);
DISPLAY 0.808511 (-8275 2475);
DISPLAY INVISIBLE (-8275 2475);
FORCEPROP 2 LAST ROOM 
J 0
(-8275 2525);
DISPLAY 0.808511 (-8275 2525);
PAINT RED (-8275 2525);
DISPLAY INVISIBLE (-8275 2525);
FORCEPROP 1 LAST PATH I190
J 0
(-8275 2475);
DISPLAY 0.978723 (-8275 2475);
PAINT WHITE (-8275 2475);
DISPLAY INVISIBLE (-8275 2475);
FORCEPROP 1 LAST PART_NUMBER CS21002FB06
J 0
(-8275 2275);
DISPLAY 0.489362 (-8275 2275);
PAINT SKYBLUE (-8275 2275);
DISPLAY INVISIBLE (-8275 2275);
FORCEADD OFFPAGE..2
(-2400 4375);
FORCEPROP 2 LAST $XR0 48 
J 0
(-2211 4375);
DISPLAY 0.638298 (-2211 4375);
PAINT MONO (-2211 4375);
FORCEPROP 2 LAST CDS_LIB mstr_standard
J 0
(-2400 4375);
DISPLAY 0.723404 (-2400 4375);
PAINT MONO (-2400 4375);
DISPLAY INVISIBLE (-2400 4375);
FORCEPROP 1 LAST OFFPAGE TRUE
J 0
(-2075 4250);
DISPLAY 0.723404 (-2075 4250);
PAINT GREEN (-2075 4250);
DISPLAY INVISIBLE (-2075 4250);
FORCEPROP 1 LAST COMMENT_BODY TRUE
J 0
(-2445 4280);
DISPLAY 0.872340 (-2445 4280);
PAINT GREEN (-2445 4280);
DISPLAY INVISIBLE (-2445 4280);
FORCEPROP 2 LAST PATH I191
J 0
(-2200 4425);
DISPLAY 0.680851 (-2200 4425);
DISPLAY INVISIBLE (-2200 4425);
FORCEADD OFFPAGE..2
(-2400 4325);
FORCEPROP 2 LAST $XR0 48 
J 0
(-2211 4325);
DISPLAY 0.638298 (-2211 4325);
PAINT MONO (-2211 4325);
FORCEPROP 2 LAST CDS_LIB mstr_standard
J 0
(-2400 4325);
DISPLAY 0.723404 (-2400 4325);
PAINT MONO (-2400 4325);
DISPLAY INVISIBLE (-2400 4325);
FORCEPROP 1 LAST OFFPAGE TRUE
J 0
(-2075 4200);
DISPLAY 0.723404 (-2075 4200);
PAINT GREEN (-2075 4200);
DISPLAY INVISIBLE (-2075 4200);
FORCEPROP 1 LAST COMMENT_BODY TRUE
J 0
(-2445 4230);
DISPLAY 0.872340 (-2445 4230);
PAINT GREEN (-2445 4230);
DISPLAY INVISIBLE (-2445 4230);
FORCEPROP 2 LAST PATH I192
J 0
(-2200 4375);
DISPLAY 0.680851 (-2200 4375);
DISPLAY INVISIBLE (-2200 4375);
FORCEADD OFFPAGE..2
(-2400 3325);
FORCEPROP 2 LAST $XR0 48 
J 0
(-2211 3325);
DISPLAY 0.638298 (-2211 3325);
PAINT MONO (-2211 3325);
FORCEPROP 2 LAST CDS_LIB mstr_standard
J 0
(-2400 3325);
DISPLAY 0.723404 (-2400 3325);
PAINT MONO (-2400 3325);
DISPLAY INVISIBLE (-2400 3325);
FORCEPROP 1 LAST OFFPAGE TRUE
J 0
(-2075 3200);
DISPLAY 0.723404 (-2075 3200);
PAINT GREEN (-2075 3200);
DISPLAY INVISIBLE (-2075 3200);
FORCEPROP 1 LAST COMMENT_BODY TRUE
J 0
(-2445 3230);
DISPLAY 0.872340 (-2445 3230);
PAINT GREEN (-2445 3230);
DISPLAY INVISIBLE (-2445 3230);
FORCEPROP 2 LAST PATH I193
J 0
(-2200 3375);
DISPLAY 0.680851 (-2200 3375);
DISPLAY INVISIBLE (-2200 3375);
FORCEADD OFFPAGE..2
(-2400 3275);
FORCEPROP 2 LAST $XR0 48 
J 0
(-2211 3275);
DISPLAY 0.638298 (-2211 3275);
PAINT MONO (-2211 3275);
FORCEPROP 2 LAST CDS_LIB mstr_standard
J 0
(-2400 3275);
DISPLAY 0.723404 (-2400 3275);
PAINT MONO (-2400 3275);
DISPLAY INVISIBLE (-2400 3275);
FORCEPROP 1 LAST OFFPAGE TRUE
J 0
(-2075 3150);
DISPLAY 0.723404 (-2075 3150);
PAINT GREEN (-2075 3150);
DISPLAY INVISIBLE (-2075 3150);
FORCEPROP 1 LAST COMMENT_BODY TRUE
J 0
(-2445 3180);
DISPLAY 0.872340 (-2445 3180);
PAINT GREEN (-2445 3180);
DISPLAY INVISIBLE (-2445 3180);
FORCEPROP 2 LAST PATH I194
J 0
(-2200 3325);
DISPLAY 0.680851 (-2200 3325);
DISPLAY INVISIBLE (-2200 3325);
FORCEADD TAP..1
(-3200 4275);
FORCEPROP 3 LASTPIN (-3250 4275) SIG_NAME M_L_CPU1_SA_DQS_DN<9>
J 0
(-3240 4285);
DISPLAY 0.659574 (-3240 4285);
PAINT MONO (-3240 4285);
DISPLAY INVISIBLE (-3240 4285);
FORCEPROP 1 LASTPIN (-3250 4275) BN 9
J 0
(-3262 4283);
DISPLAY 0.489362 (-3262 4283);
PAINT GREEN (-3262 4283);
FORCEPROP 2 LAST CDS_LIB mstr_standard
J 0
(-3200 4275);
DISPLAY 0.723404 (-3200 4275);
PAINT MONO (-3200 4275);
DISPLAY INVISIBLE (-3200 4275);
FORCEPROP 1 LAST BODY_TYPE PLUMBING
J 0
(-3200 4325);
DISPLAY 0.872340 (-3200 4325);
PAINT GREEN (-3200 4325);
DISPLAY INVISIBLE (-3200 4325);
FORCEPROP 1 LAST HDL_TAP TRUE
J 0
(-2875 4150);
DISPLAY 0.872340 (-2875 4150);
DISPLAY INVISIBLE (-2875 4150);
FORCEPROP 1 LAST PATH I195
J 0
(-3202 4275);
DISPLAY 0.872340 (-3202 4275);
PAINT GREEN (-3202 4275);
DISPLAY INVISIBLE (-3202 4275);
FORCEADD TAP..1
(-3200 4175);
FORCEPROP 3 LASTPIN (-3250 4175) SIG_NAME M_L_CPU1_SA_DQS_DN<8>
J 0
(-3240 4185);
DISPLAY 0.659574 (-3240 4185);
PAINT MONO (-3240 4185);
DISPLAY INVISIBLE (-3240 4185);
FORCEPROP 1 LASTPIN (-3250 4175) BN 8
J 0
(-3262 4183);
DISPLAY 0.489362 (-3262 4183);
PAINT GREEN (-3262 4183);
FORCEPROP 2 LAST CDS_LIB mstr_standard
J 0
(-3200 4175);
DISPLAY 0.723404 (-3200 4175);
PAINT MONO (-3200 4175);
DISPLAY INVISIBLE (-3200 4175);
FORCEPROP 1 LAST BODY_TYPE PLUMBING
J 0
(-3200 4225);
DISPLAY 0.872340 (-3200 4225);
PAINT GREEN (-3200 4225);
DISPLAY INVISIBLE (-3200 4225);
FORCEPROP 1 LAST HDL_TAP TRUE
J 0
(-2875 4050);
DISPLAY 0.872340 (-2875 4050);
DISPLAY INVISIBLE (-2875 4050);
FORCEPROP 1 LAST PATH I196
J 0
(-3202 4175);
DISPLAY 0.872340 (-3202 4175);
PAINT GREEN (-3202 4175);
DISPLAY INVISIBLE (-3202 4175);
FORCEADD TAP..1
(-3400 4225);
FORCEPROP 3 LASTPIN (-3450 4225) SIG_NAME M_L_CPU1_SA_DQS_DP<8>
J 0
(-3440 4235);
DISPLAY 0.659574 (-3440 4235);
PAINT MONO (-3440 4235);
DISPLAY INVISIBLE (-3440 4235);
FORCEPROP 1 LASTPIN (-3450 4225) BN 8
J 0
(-3462 4233);
DISPLAY 0.489362 (-3462 4233);
PAINT GREEN (-3462 4233);
FORCEPROP 2 LAST CDS_LIB mstr_standard
J 0
(-3400 4225);
DISPLAY 0.723404 (-3400 4225);
PAINT MONO (-3400 4225);
DISPLAY INVISIBLE (-3400 4225);
FORCEPROP 1 LAST BODY_TYPE PLUMBING
J 0
(-3400 4275);
DISPLAY 0.872340 (-3400 4275);
PAINT GREEN (-3400 4275);
DISPLAY INVISIBLE (-3400 4275);
FORCEPROP 1 LAST HDL_TAP TRUE
J 0
(-3075 4100);
DISPLAY 0.872340 (-3075 4100);
DISPLAY INVISIBLE (-3075 4100);
FORCEPROP 1 LAST PATH I197
J 0
(-3402 4225);
DISPLAY 0.872340 (-3402 4225);
PAINT GREEN (-3402 4225);
DISPLAY INVISIBLE (-3402 4225);
FORCEADD TAP..1
(-3400 4125);
FORCEPROP 3 LASTPIN (-3450 4125) SIG_NAME M_L_CPU1_SA_DQS_DP<7>
J 0
(-3440 4135);
DISPLAY 0.659574 (-3440 4135);
PAINT MONO (-3440 4135);
DISPLAY INVISIBLE (-3440 4135);
FORCEPROP 1 LASTPIN (-3450 4125) BN 7
J 0
(-3462 4133);
DISPLAY 0.489362 (-3462 4133);
PAINT GREEN (-3462 4133);
FORCEPROP 2 LAST CDS_LIB mstr_standard
J 0
(-3400 4125);
DISPLAY 0.723404 (-3400 4125);
PAINT MONO (-3400 4125);
DISPLAY INVISIBLE (-3400 4125);
FORCEPROP 1 LAST BODY_TYPE PLUMBING
J 0
(-3400 4175);
DISPLAY 0.872340 (-3400 4175);
PAINT GREEN (-3400 4175);
DISPLAY INVISIBLE (-3400 4175);
FORCEPROP 1 LAST HDL_TAP TRUE
J 0
(-3075 4000);
DISPLAY 0.872340 (-3075 4000);
DISPLAY INVISIBLE (-3075 4000);
FORCEPROP 1 LAST PATH I198
J 0
(-3402 4125);
DISPLAY 0.872340 (-3402 4125);
PAINT GREEN (-3402 4125);
DISPLAY INVISIBLE (-3402 4125);
FORCEADD TAP..1
(-3400 4325);
FORCEPROP 3 LASTPIN (-3450 4325) SIG_NAME M_L_CPU1_SA_DQS_DP<9>
J 0
(-3440 4335);
DISPLAY 0.659574 (-3440 4335);
PAINT MONO (-3440 4335);
DISPLAY INVISIBLE (-3440 4335);
FORCEPROP 1 LASTPIN (-3450 4325) BN 9
J 0
(-3462 4333);
DISPLAY 0.489362 (-3462 4333);
PAINT GREEN (-3462 4333);
FORCEPROP 2 LAST CDS_LIB mstr_standard
J 0
(-3400 4325);
DISPLAY 0.723404 (-3400 4325);
PAINT MONO (-3400 4325);
DISPLAY INVISIBLE (-3400 4325);
FORCEPROP 1 LAST BODY_TYPE PLUMBING
J 0
(-3400 4375);
DISPLAY 0.872340 (-3400 4375);
PAINT GREEN (-3400 4375);
DISPLAY INVISIBLE (-3400 4375);
FORCEPROP 1 LAST HDL_TAP TRUE
J 0
(-3075 4200);
DISPLAY 0.872340 (-3075 4200);
DISPLAY INVISIBLE (-3075 4200);
FORCEPROP 1 LAST PATH I199
J 0
(-3402 4325);
DISPLAY 0.872340 (-3402 4325);
PAINT GREEN (-3402 4325);
DISPLAY INVISIBLE (-3402 4325);
FORCEADD OFFPAGE..5
(-8250 2000);
FORCEPROP 2 LAST $XR0 48 
J 0
(-8474 2000);
DISPLAY 0.638298 (-8474 2000);
PAINT MONO (-8474 2000);
FORCEPROP 2 LAST CDS_LIB mstr_standard
J 0
(-8250 2000);
DISPLAY 0.808511 (-8250 2000);
DISPLAY INVISIBLE (-8250 2000);
FORCEPROP 1 LAST OFFPAGE TRUE
J 0
(-7925 1875);
DISPLAY 0.872340 (-7925 1875);
PAINT GREEN (-7925 1875);
DISPLAY INVISIBLE (-7925 1875);
FORCEPROP 1 LAST COMMENT_BODY TRUE
J 0
(-8150 1925);
DISPLAY 0.872340 (-8150 1925);
PAINT GREEN (-8150 1925);
DISPLAY INVISIBLE (-8150 1925);
FORCEPROP 2 LAST PATH I2
J 0
(-8500 2050);
DISPLAY 1.021277 (-8500 2050);
DISPLAY INVISIBLE (-8500 2050);
FORCEADD OFFPAGE..1
(-8250 5050);
FORCEPROP 2 LAST $XR0 48 
J 0
(-8501 5050);
DISPLAY 0.638298 (-8501 5050);
PAINT MONO (-8501 5050);
FORCEPROP 2 LAST CDS_LIB mstr_standard
J 0
(-8250 5050);
DISPLAY 0.723404 (-8250 5050);
PAINT MONO (-8250 5050);
DISPLAY INVISIBLE (-8250 5050);
FORCEPROP 1 LAST OFFPAGE TRUE
J 0
(-7925 4925);
DISPLAY 0.872340 (-7925 4925);
PAINT GREEN (-7925 4925);
DISPLAY INVISIBLE (-7925 4925);
FORCEPROP 1 LAST COMMENT_BODY TRUE
J 0
(-8125 4950);
DISPLAY 0.872340 (-8125 4950);
PAINT GREEN (-8125 4950);
DISPLAY INVISIBLE (-8125 4950);
FORCEPROP 2 LAST PATH I20
J 0
(-8450 5100);
DISPLAY 1.021277 (-8450 5100);
DISPLAY INVISIBLE (-8450 5100);
FORCEADD TAP..1
(-3200 4075);
FORCEPROP 3 LASTPIN (-3250 4075) SIG_NAME M_L_CPU1_SA_DQS_DN<7>
J 0
(-3240 4085);
DISPLAY 0.659574 (-3240 4085);
PAINT MONO (-3240 4085);
DISPLAY INVISIBLE (-3240 4085);
FORCEPROP 1 LASTPIN (-3250 4075) BN 7
J 0
(-3262 4083);
DISPLAY 0.489362 (-3262 4083);
PAINT GREEN (-3262 4083);
FORCEPROP 2 LAST CDS_LIB mstr_standard
J 0
(-3200 4075);
DISPLAY 0.723404 (-3200 4075);
PAINT MONO (-3200 4075);
DISPLAY INVISIBLE (-3200 4075);
FORCEPROP 1 LAST BODY_TYPE PLUMBING
J 0
(-3200 4125);
DISPLAY 0.872340 (-3200 4125);
PAINT GREEN (-3200 4125);
DISPLAY INVISIBLE (-3200 4125);
FORCEPROP 1 LAST HDL_TAP TRUE
J 0
(-2875 3950);
DISPLAY 0.872340 (-2875 3950);
DISPLAY INVISIBLE (-2875 3950);
FORCEPROP 1 LAST PATH I200
J 0
(-3202 4075);
DISPLAY 0.872340 (-3202 4075);
PAINT GREEN (-3202 4075);
DISPLAY INVISIBLE (-3202 4075);
FORCEADD TAP..1
(-3200 3975);
FORCEPROP 3 LASTPIN (-3250 3975) SIG_NAME M_L_CPU1_SA_DQS_DN<6>
J 0
(-3240 3985);
DISPLAY 0.659574 (-3240 3985);
PAINT MONO (-3240 3985);
DISPLAY INVISIBLE (-3240 3985);
FORCEPROP 1 LASTPIN (-3250 3975) BN 6
J 0
(-3262 3983);
DISPLAY 0.489362 (-3262 3983);
PAINT GREEN (-3262 3983);
FORCEPROP 2 LAST CDS_LIB mstr_standard
J 0
(-3200 3975);
DISPLAY 0.723404 (-3200 3975);
PAINT MONO (-3200 3975);
DISPLAY INVISIBLE (-3200 3975);
FORCEPROP 1 LAST BODY_TYPE PLUMBING
J 0
(-3200 4025);
DISPLAY 0.872340 (-3200 4025);
PAINT GREEN (-3200 4025);
DISPLAY INVISIBLE (-3200 4025);
FORCEPROP 1 LAST HDL_TAP TRUE
J 0
(-2875 3850);
DISPLAY 0.872340 (-2875 3850);
DISPLAY INVISIBLE (-2875 3850);
FORCEPROP 1 LAST PATH I201
J 0
(-3202 3975);
DISPLAY 0.872340 (-3202 3975);
PAINT GREEN (-3202 3975);
DISPLAY INVISIBLE (-3202 3975);
FORCEADD TAP..1
(-3200 3875);
FORCEPROP 3 LASTPIN (-3250 3875) SIG_NAME M_L_CPU1_SA_DQS_DN<5>
J 0
(-3240 3885);
DISPLAY 0.659574 (-3240 3885);
PAINT MONO (-3240 3885);
DISPLAY INVISIBLE (-3240 3885);
FORCEPROP 1 LASTPIN (-3250 3875) BN 5
J 0
(-3262 3883);
DISPLAY 0.489362 (-3262 3883);
PAINT GREEN (-3262 3883);
FORCEPROP 2 LAST CDS_LIB mstr_standard
J 0
(-3200 3875);
DISPLAY 0.723404 (-3200 3875);
PAINT MONO (-3200 3875);
DISPLAY INVISIBLE (-3200 3875);
FORCEPROP 1 LAST BODY_TYPE PLUMBING
J 0
(-3200 3925);
DISPLAY 0.872340 (-3200 3925);
PAINT GREEN (-3200 3925);
DISPLAY INVISIBLE (-3200 3925);
FORCEPROP 1 LAST HDL_TAP TRUE
J 0
(-2875 3750);
DISPLAY 0.872340 (-2875 3750);
DISPLAY INVISIBLE (-2875 3750);
FORCEPROP 1 LAST PATH I202
J 0
(-3202 3875);
DISPLAY 0.872340 (-3202 3875);
PAINT GREEN (-3202 3875);
DISPLAY INVISIBLE (-3202 3875);
FORCEADD TAP..1
(-3200 3775);
FORCEPROP 3 LASTPIN (-3250 3775) SIG_NAME M_L_CPU1_SA_DQS_DN<4>
J 0
(-3240 3785);
DISPLAY 0.659574 (-3240 3785);
PAINT MONO (-3240 3785);
DISPLAY INVISIBLE (-3240 3785);
FORCEPROP 1 LASTPIN (-3250 3775) BN 4
J 0
(-3262 3783);
DISPLAY 0.489362 (-3262 3783);
PAINT GREEN (-3262 3783);
FORCEPROP 2 LAST CDS_LIB mstr_standard
J 0
(-3200 3775);
DISPLAY 0.723404 (-3200 3775);
PAINT MONO (-3200 3775);
DISPLAY INVISIBLE (-3200 3775);
FORCEPROP 1 LAST BODY_TYPE PLUMBING
J 0
(-3200 3825);
DISPLAY 0.872340 (-3200 3825);
PAINT GREEN (-3200 3825);
DISPLAY INVISIBLE (-3200 3825);
FORCEPROP 1 LAST HDL_TAP TRUE
J 0
(-2875 3650);
DISPLAY 0.872340 (-2875 3650);
DISPLAY INVISIBLE (-2875 3650);
FORCEPROP 1 LAST PATH I203
J 0
(-3202 3775);
DISPLAY 0.872340 (-3202 3775);
PAINT GREEN (-3202 3775);
DISPLAY INVISIBLE (-3202 3775);
FORCEADD TAP..1
(-3200 3675);
FORCEPROP 3 LASTPIN (-3250 3675) SIG_NAME M_L_CPU1_SA_DQS_DN<3>
J 0
(-3240 3685);
DISPLAY 0.659574 (-3240 3685);
PAINT MONO (-3240 3685);
DISPLAY INVISIBLE (-3240 3685);
FORCEPROP 1 LASTPIN (-3250 3675) BN 3
J 0
(-3262 3683);
DISPLAY 0.489362 (-3262 3683);
PAINT GREEN (-3262 3683);
FORCEPROP 2 LAST CDS_LIB mstr_standard
J 0
(-3200 3675);
DISPLAY 0.723404 (-3200 3675);
PAINT MONO (-3200 3675);
DISPLAY INVISIBLE (-3200 3675);
FORCEPROP 1 LAST BODY_TYPE PLUMBING
J 0
(-3200 3725);
DISPLAY 0.872340 (-3200 3725);
PAINT GREEN (-3200 3725);
DISPLAY INVISIBLE (-3200 3725);
FORCEPROP 1 LAST HDL_TAP TRUE
J 0
(-2875 3550);
DISPLAY 0.872340 (-2875 3550);
DISPLAY INVISIBLE (-2875 3550);
FORCEPROP 1 LAST PATH I204
J 0
(-3202 3675);
DISPLAY 0.872340 (-3202 3675);
PAINT GREEN (-3202 3675);
DISPLAY INVISIBLE (-3202 3675);
FORCEADD TAP..1
(-3200 3575);
FORCEPROP 3 LASTPIN (-3250 3575) SIG_NAME M_L_CPU1_SA_DQS_DN<2>
J 0
(-3240 3585);
DISPLAY 0.659574 (-3240 3585);
PAINT MONO (-3240 3585);
DISPLAY INVISIBLE (-3240 3585);
FORCEPROP 1 LASTPIN (-3250 3575) BN 2
J 0
(-3262 3583);
DISPLAY 0.489362 (-3262 3583);
PAINT GREEN (-3262 3583);
FORCEPROP 2 LAST CDS_LIB mstr_standard
J 0
(-3200 3575);
DISPLAY 0.723404 (-3200 3575);
PAINT MONO (-3200 3575);
DISPLAY INVISIBLE (-3200 3575);
FORCEPROP 1 LAST BODY_TYPE PLUMBING
J 0
(-3200 3625);
DISPLAY 0.872340 (-3200 3625);
PAINT GREEN (-3200 3625);
DISPLAY INVISIBLE (-3200 3625);
FORCEPROP 1 LAST HDL_TAP TRUE
J 0
(-2875 3450);
DISPLAY 0.872340 (-2875 3450);
DISPLAY INVISIBLE (-2875 3450);
FORCEPROP 1 LAST PATH I205
J 0
(-3202 3575);
DISPLAY 0.872340 (-3202 3575);
PAINT GREEN (-3202 3575);
DISPLAY INVISIBLE (-3202 3575);
FORCEADD TAP..1
(-3200 3375);
FORCEPROP 3 LASTPIN (-3250 3375) SIG_NAME M_L_CPU1_SA_DQS_DN<0>
J 0
(-3240 3385);
DISPLAY 0.659574 (-3240 3385);
PAINT MONO (-3240 3385);
DISPLAY INVISIBLE (-3240 3385);
FORCEPROP 1 LASTPIN (-3250 3375) BN 0
J 0
(-3262 3383);
DISPLAY 0.489362 (-3262 3383);
PAINT GREEN (-3262 3383);
FORCEPROP 2 LAST CDS_LIB mstr_standard
J 0
(-3200 3375);
DISPLAY 0.723404 (-3200 3375);
PAINT MONO (-3200 3375);
DISPLAY INVISIBLE (-3200 3375);
FORCEPROP 1 LAST BODY_TYPE PLUMBING
J 0
(-3200 3425);
DISPLAY 0.872340 (-3200 3425);
PAINT GREEN (-3200 3425);
DISPLAY INVISIBLE (-3200 3425);
FORCEPROP 1 LAST HDL_TAP TRUE
J 0
(-2875 3250);
DISPLAY 0.872340 (-2875 3250);
DISPLAY INVISIBLE (-2875 3250);
FORCEPROP 1 LAST PATH I206
J 0
(-3202 3375);
DISPLAY 0.872340 (-3202 3375);
PAINT GREEN (-3202 3375);
DISPLAY INVISIBLE (-3202 3375);
FORCEADD TAP..1
(-3200 3475);
FORCEPROP 3 LASTPIN (-3250 3475) SIG_NAME M_L_CPU1_SA_DQS_DN<1>
J 0
(-3240 3485);
DISPLAY 0.659574 (-3240 3485);
PAINT MONO (-3240 3485);
DISPLAY INVISIBLE (-3240 3485);
FORCEPROP 1 LASTPIN (-3250 3475) BN 1
J 0
(-3262 3483);
DISPLAY 0.489362 (-3262 3483);
PAINT GREEN (-3262 3483);
FORCEPROP 2 LAST CDS_LIB mstr_standard
J 0
(-3200 3475);
DISPLAY 0.723404 (-3200 3475);
PAINT MONO (-3200 3475);
DISPLAY INVISIBLE (-3200 3475);
FORCEPROP 1 LAST BODY_TYPE PLUMBING
J 0
(-3200 3525);
DISPLAY 0.872340 (-3200 3525);
PAINT GREEN (-3200 3525);
DISPLAY INVISIBLE (-3200 3525);
FORCEPROP 1 LAST HDL_TAP TRUE
J 0
(-2875 3350);
DISPLAY 0.872340 (-2875 3350);
DISPLAY INVISIBLE (-2875 3350);
FORCEPROP 1 LAST PATH I207
J 0
(-3202 3475);
DISPLAY 0.872340 (-3202 3475);
PAINT GREEN (-3202 3475);
DISPLAY INVISIBLE (-3202 3475);
FORCEADD TAP..1
(-3200 3225);
FORCEPROP 3 LASTPIN (-3250 3225) SIG_NAME M_L_CPU1_SB_DQS_DN<9>
J 0
(-3240 3235);
DISPLAY 0.659574 (-3240 3235);
PAINT MONO (-3240 3235);
DISPLAY INVISIBLE (-3240 3235);
FORCEPROP 1 LASTPIN (-3250 3225) BN 9
J 0
(-3262 3233);
DISPLAY 0.489362 (-3262 3233);
PAINT GREEN (-3262 3233);
FORCEPROP 2 LAST CDS_LIB mstr_standard
J 0
(-3200 3225);
DISPLAY 0.723404 (-3200 3225);
PAINT MONO (-3200 3225);
DISPLAY INVISIBLE (-3200 3225);
FORCEPROP 1 LAST BODY_TYPE PLUMBING
J 0
(-3200 3275);
DISPLAY 0.872340 (-3200 3275);
PAINT GREEN (-3200 3275);
DISPLAY INVISIBLE (-3200 3275);
FORCEPROP 1 LAST HDL_TAP TRUE
J 0
(-2875 3100);
DISPLAY 0.872340 (-2875 3100);
DISPLAY INVISIBLE (-2875 3100);
FORCEPROP 1 LAST PATH I208
J 0
(-3202 3225);
DISPLAY 0.872340 (-3202 3225);
PAINT GREEN (-3202 3225);
DISPLAY INVISIBLE (-3202 3225);
FORCEADD TAP..1
(-3200 3125);
FORCEPROP 3 LASTPIN (-3250 3125) SIG_NAME M_L_CPU1_SB_DQS_DN<8>
J 0
(-3240 3135);
DISPLAY 0.659574 (-3240 3135);
PAINT MONO (-3240 3135);
DISPLAY INVISIBLE (-3240 3135);
FORCEPROP 1 LASTPIN (-3250 3125) BN 8
J 0
(-3262 3133);
DISPLAY 0.489362 (-3262 3133);
PAINT GREEN (-3262 3133);
FORCEPROP 2 LAST CDS_LIB mstr_standard
J 0
(-3200 3125);
DISPLAY 0.723404 (-3200 3125);
PAINT MONO (-3200 3125);
DISPLAY INVISIBLE (-3200 3125);
FORCEPROP 1 LAST BODY_TYPE PLUMBING
J 0
(-3200 3175);
DISPLAY 0.872340 (-3200 3175);
PAINT GREEN (-3200 3175);
DISPLAY INVISIBLE (-3200 3175);
FORCEPROP 1 LAST HDL_TAP TRUE
J 0
(-2875 3000);
DISPLAY 0.872340 (-2875 3000);
DISPLAY INVISIBLE (-2875 3000);
FORCEPROP 1 LAST PATH I209
J 0
(-3202 3125);
DISPLAY 0.872340 (-3202 3125);
PAINT GREEN (-3202 3125);
DISPLAY INVISIBLE (-3202 3125);
FORCEADD OFFPAGE..1
(-8250 5450);
FORCEPROP 2 LAST $XR0 48 
J 0
(-8501 5450);
DISPLAY 0.638298 (-8501 5450);
PAINT MONO (-8501 5450);
FORCEPROP 2 LAST CDS_LIB mstr_standard
J 0
(-8250 5450);
DISPLAY 0.723404 (-8250 5450);
PAINT MONO (-8250 5450);
DISPLAY INVISIBLE (-8250 5450);
FORCEPROP 1 LAST OFFPAGE TRUE
J 0
(-7925 5325);
DISPLAY 0.872340 (-7925 5325);
PAINT GREEN (-7925 5325);
DISPLAY INVISIBLE (-7925 5325);
FORCEPROP 1 LAST COMMENT_BODY TRUE
J 0
(-8125 5350);
DISPLAY 0.872340 (-8125 5350);
PAINT GREEN (-8125 5350);
DISPLAY INVISIBLE (-8125 5350);
FORCEPROP 2 LAST PATH I21
J 0
(-8450 5500);
DISPLAY 1.021277 (-8450 5500);
DISPLAY INVISIBLE (-8450 5500);
FORCEADD TAP..1
(-3400 3925);
FORCEPROP 3 LASTPIN (-3450 3925) SIG_NAME M_L_CPU1_SA_DQS_DP<5>
J 0
(-3440 3935);
DISPLAY 0.659574 (-3440 3935);
PAINT MONO (-3440 3935);
DISPLAY INVISIBLE (-3440 3935);
FORCEPROP 1 LASTPIN (-3450 3925) BN 5
J 0
(-3462 3933);
DISPLAY 0.489362 (-3462 3933);
PAINT GREEN (-3462 3933);
FORCEPROP 2 LAST CDS_LIB mstr_standard
J 0
(-3400 3925);
DISPLAY 0.723404 (-3400 3925);
PAINT MONO (-3400 3925);
DISPLAY INVISIBLE (-3400 3925);
FORCEPROP 1 LAST BODY_TYPE PLUMBING
J 0
(-3400 3975);
DISPLAY 0.872340 (-3400 3975);
PAINT GREEN (-3400 3975);
DISPLAY INVISIBLE (-3400 3975);
FORCEPROP 1 LAST HDL_TAP TRUE
J 0
(-3075 3800);
DISPLAY 0.872340 (-3075 3800);
DISPLAY INVISIBLE (-3075 3800);
FORCEPROP 1 LAST PATH I210
J 0
(-3402 3925);
DISPLAY 0.872340 (-3402 3925);
PAINT GREEN (-3402 3925);
DISPLAY INVISIBLE (-3402 3925);
FORCEADD TAP..1
(-3400 4025);
FORCEPROP 3 LASTPIN (-3450 4025) SIG_NAME M_L_CPU1_SA_DQS_DP<6>
J 0
(-3440 4035);
DISPLAY 0.659574 (-3440 4035);
PAINT MONO (-3440 4035);
DISPLAY INVISIBLE (-3440 4035);
FORCEPROP 1 LASTPIN (-3450 4025) BN 6
J 0
(-3462 4033);
DISPLAY 0.489362 (-3462 4033);
PAINT GREEN (-3462 4033);
FORCEPROP 2 LAST CDS_LIB mstr_standard
J 0
(-3400 4025);
DISPLAY 0.723404 (-3400 4025);
PAINT MONO (-3400 4025);
DISPLAY INVISIBLE (-3400 4025);
FORCEPROP 1 LAST BODY_TYPE PLUMBING
J 0
(-3400 4075);
DISPLAY 0.872340 (-3400 4075);
PAINT GREEN (-3400 4075);
DISPLAY INVISIBLE (-3400 4075);
FORCEPROP 1 LAST HDL_TAP TRUE
J 0
(-3075 3900);
DISPLAY 0.872340 (-3075 3900);
DISPLAY INVISIBLE (-3075 3900);
FORCEPROP 1 LAST PATH I211
J 0
(-3402 4025);
DISPLAY 0.872340 (-3402 4025);
PAINT GREEN (-3402 4025);
DISPLAY INVISIBLE (-3402 4025);
FORCEADD TAP..1
(-3400 3825);
FORCEPROP 3 LASTPIN (-3450 3825) SIG_NAME M_L_CPU1_SA_DQS_DP<4>
J 0
(-3440 3835);
DISPLAY 0.659574 (-3440 3835);
PAINT MONO (-3440 3835);
DISPLAY INVISIBLE (-3440 3835);
FORCEPROP 1 LASTPIN (-3450 3825) BN 4
J 0
(-3462 3833);
DISPLAY 0.489362 (-3462 3833);
PAINT GREEN (-3462 3833);
FORCEPROP 2 LAST CDS_LIB mstr_standard
J 0
(-3400 3825);
DISPLAY 0.723404 (-3400 3825);
PAINT MONO (-3400 3825);
DISPLAY INVISIBLE (-3400 3825);
FORCEPROP 1 LAST BODY_TYPE PLUMBING
J 0
(-3400 3875);
DISPLAY 0.872340 (-3400 3875);
PAINT GREEN (-3400 3875);
DISPLAY INVISIBLE (-3400 3875);
FORCEPROP 1 LAST HDL_TAP TRUE
J 0
(-3075 3700);
DISPLAY 0.872340 (-3075 3700);
DISPLAY INVISIBLE (-3075 3700);
FORCEPROP 1 LAST PATH I212
J 0
(-3402 3825);
DISPLAY 0.872340 (-3402 3825);
PAINT GREEN (-3402 3825);
DISPLAY INVISIBLE (-3402 3825);
FORCEADD TAP..1
(-3400 3725);
FORCEPROP 3 LASTPIN (-3450 3725) SIG_NAME M_L_CPU1_SA_DQS_DP<3>
J 0
(-3440 3735);
DISPLAY 0.659574 (-3440 3735);
PAINT MONO (-3440 3735);
DISPLAY INVISIBLE (-3440 3735);
FORCEPROP 1 LASTPIN (-3450 3725) BN 3
J 0
(-3462 3733);
DISPLAY 0.489362 (-3462 3733);
PAINT GREEN (-3462 3733);
FORCEPROP 2 LAST CDS_LIB mstr_standard
J 0
(-3400 3725);
DISPLAY 0.723404 (-3400 3725);
PAINT MONO (-3400 3725);
DISPLAY INVISIBLE (-3400 3725);
FORCEPROP 1 LAST BODY_TYPE PLUMBING
J 0
(-3400 3775);
DISPLAY 0.872340 (-3400 3775);
PAINT GREEN (-3400 3775);
DISPLAY INVISIBLE (-3400 3775);
FORCEPROP 1 LAST HDL_TAP TRUE
J 0
(-3075 3600);
DISPLAY 0.872340 (-3075 3600);
DISPLAY INVISIBLE (-3075 3600);
FORCEPROP 1 LAST PATH I213
J 0
(-3402 3725);
DISPLAY 0.872340 (-3402 3725);
PAINT GREEN (-3402 3725);
DISPLAY INVISIBLE (-3402 3725);
FORCEADD TAP..1
(-3400 3625);
FORCEPROP 3 LASTPIN (-3450 3625) SIG_NAME M_L_CPU1_SA_DQS_DP<2>
J 0
(-3440 3635);
DISPLAY 0.659574 (-3440 3635);
PAINT MONO (-3440 3635);
DISPLAY INVISIBLE (-3440 3635);
FORCEPROP 1 LASTPIN (-3450 3625) BN 2
J 0
(-3462 3633);
DISPLAY 0.489362 (-3462 3633);
PAINT GREEN (-3462 3633);
FORCEPROP 2 LAST CDS_LIB mstr_standard
J 0
(-3400 3625);
DISPLAY 0.723404 (-3400 3625);
PAINT MONO (-3400 3625);
DISPLAY INVISIBLE (-3400 3625);
FORCEPROP 1 LAST BODY_TYPE PLUMBING
J 0
(-3400 3675);
DISPLAY 0.872340 (-3400 3675);
PAINT GREEN (-3400 3675);
DISPLAY INVISIBLE (-3400 3675);
FORCEPROP 1 LAST HDL_TAP TRUE
J 0
(-3075 3500);
DISPLAY 0.872340 (-3075 3500);
DISPLAY INVISIBLE (-3075 3500);
FORCEPROP 1 LAST PATH I214
J 0
(-3402 3625);
DISPLAY 0.872340 (-3402 3625);
PAINT GREEN (-3402 3625);
DISPLAY INVISIBLE (-3402 3625);
FORCEADD TAP..1
(-3400 3425);
FORCEPROP 3 LASTPIN (-3450 3425) SIG_NAME M_L_CPU1_SA_DQS_DP<0>
J 0
(-3440 3435);
DISPLAY 0.659574 (-3440 3435);
PAINT MONO (-3440 3435);
DISPLAY INVISIBLE (-3440 3435);
FORCEPROP 1 LASTPIN (-3450 3425) BN 0
J 0
(-3462 3433);
DISPLAY 0.489362 (-3462 3433);
PAINT GREEN (-3462 3433);
FORCEPROP 2 LAST CDS_LIB mstr_standard
J 0
(-3400 3425);
DISPLAY 0.723404 (-3400 3425);
PAINT MONO (-3400 3425);
DISPLAY INVISIBLE (-3400 3425);
FORCEPROP 1 LAST BODY_TYPE PLUMBING
J 0
(-3400 3475);
DISPLAY 0.872340 (-3400 3475);
PAINT GREEN (-3400 3475);
DISPLAY INVISIBLE (-3400 3475);
FORCEPROP 1 LAST HDL_TAP TRUE
J 0
(-3075 3300);
DISPLAY 0.872340 (-3075 3300);
DISPLAY INVISIBLE (-3075 3300);
FORCEPROP 1 LAST PATH I215
J 0
(-3402 3425);
DISPLAY 0.872340 (-3402 3425);
PAINT GREEN (-3402 3425);
DISPLAY INVISIBLE (-3402 3425);
FORCEADD TAP..1
(-3400 3525);
FORCEPROP 3 LASTPIN (-3450 3525) SIG_NAME M_L_CPU1_SA_DQS_DP<1>
J 0
(-3440 3535);
DISPLAY 0.659574 (-3440 3535);
PAINT MONO (-3440 3535);
DISPLAY INVISIBLE (-3440 3535);
FORCEPROP 1 LASTPIN (-3450 3525) BN 1
J 0
(-3462 3533);
DISPLAY 0.489362 (-3462 3533);
PAINT GREEN (-3462 3533);
FORCEPROP 2 LAST CDS_LIB mstr_standard
J 0
(-3400 3525);
DISPLAY 0.723404 (-3400 3525);
PAINT MONO (-3400 3525);
DISPLAY INVISIBLE (-3400 3525);
FORCEPROP 1 LAST BODY_TYPE PLUMBING
J 0
(-3400 3575);
DISPLAY 0.872340 (-3400 3575);
PAINT GREEN (-3400 3575);
DISPLAY INVISIBLE (-3400 3575);
FORCEPROP 1 LAST HDL_TAP TRUE
J 0
(-3075 3400);
DISPLAY 0.872340 (-3075 3400);
DISPLAY INVISIBLE (-3075 3400);
FORCEPROP 1 LAST PATH I216
J 0
(-3402 3525);
DISPLAY 0.872340 (-3402 3525);
PAINT GREEN (-3402 3525);
DISPLAY INVISIBLE (-3402 3525);
FORCEADD TAP..1
(-3400 3275);
FORCEPROP 3 LASTPIN (-3450 3275) SIG_NAME M_L_CPU1_SB_DQS_DP<9>
J 0
(-3440 3285);
DISPLAY 0.659574 (-3440 3285);
PAINT MONO (-3440 3285);
DISPLAY INVISIBLE (-3440 3285);
FORCEPROP 1 LASTPIN (-3450 3275) BN 9
J 0
(-3462 3283);
DISPLAY 0.489362 (-3462 3283);
PAINT GREEN (-3462 3283);
FORCEPROP 2 LAST CDS_LIB mstr_standard
J 0
(-3400 3275);
DISPLAY 0.723404 (-3400 3275);
PAINT MONO (-3400 3275);
DISPLAY INVISIBLE (-3400 3275);
FORCEPROP 1 LAST BODY_TYPE PLUMBING
J 0
(-3400 3325);
DISPLAY 0.872340 (-3400 3325);
PAINT GREEN (-3400 3325);
DISPLAY INVISIBLE (-3400 3325);
FORCEPROP 1 LAST HDL_TAP TRUE
J 0
(-3075 3150);
DISPLAY 0.872340 (-3075 3150);
DISPLAY INVISIBLE (-3075 3150);
FORCEPROP 1 LAST PATH I217
J 0
(-3402 3275);
DISPLAY 0.872340 (-3402 3275);
PAINT GREEN (-3402 3275);
DISPLAY INVISIBLE (-3402 3275);
FORCEADD TAP..1
(-3400 3175);
FORCEPROP 3 LASTPIN (-3450 3175) SIG_NAME M_L_CPU1_SB_DQS_DP<8>
J 0
(-3440 3185);
DISPLAY 0.659574 (-3440 3185);
PAINT MONO (-3440 3185);
DISPLAY INVISIBLE (-3440 3185);
FORCEPROP 1 LASTPIN (-3450 3175) BN 8
J 0
(-3462 3183);
DISPLAY 0.489362 (-3462 3183);
PAINT GREEN (-3462 3183);
FORCEPROP 2 LAST CDS_LIB mstr_standard
J 0
(-3400 3175);
DISPLAY 0.723404 (-3400 3175);
PAINT MONO (-3400 3175);
DISPLAY INVISIBLE (-3400 3175);
FORCEPROP 1 LAST BODY_TYPE PLUMBING
J 0
(-3400 3225);
DISPLAY 0.872340 (-3400 3225);
PAINT GREEN (-3400 3225);
DISPLAY INVISIBLE (-3400 3225);
FORCEPROP 1 LAST HDL_TAP TRUE
J 0
(-3075 3050);
DISPLAY 0.872340 (-3075 3050);
DISPLAY INVISIBLE (-3075 3050);
FORCEPROP 1 LAST PATH I218
J 0
(-3402 3175);
DISPLAY 0.872340 (-3402 3175);
PAINT GREEN (-3402 3175);
DISPLAY INVISIBLE (-3402 3175);
FORCEADD TAP..1
(-3200 3025);
FORCEPROP 3 LASTPIN (-3250 3025) SIG_NAME M_L_CPU1_SB_DQS_DN<7>
J 0
(-3240 3035);
DISPLAY 0.659574 (-3240 3035);
PAINT MONO (-3240 3035);
DISPLAY INVISIBLE (-3240 3035);
FORCEPROP 1 LASTPIN (-3250 3025) BN 7
J 0
(-3262 3033);
DISPLAY 0.489362 (-3262 3033);
PAINT GREEN (-3262 3033);
FORCEPROP 2 LAST CDS_LIB mstr_standard
J 0
(-3200 3025);
DISPLAY 0.723404 (-3200 3025);
PAINT MONO (-3200 3025);
DISPLAY INVISIBLE (-3200 3025);
FORCEPROP 1 LAST BODY_TYPE PLUMBING
J 0
(-3200 3075);
DISPLAY 0.872340 (-3200 3075);
PAINT GREEN (-3200 3075);
DISPLAY INVISIBLE (-3200 3075);
FORCEPROP 1 LAST HDL_TAP TRUE
J 0
(-2875 2900);
DISPLAY 0.872340 (-2875 2900);
DISPLAY INVISIBLE (-2875 2900);
FORCEPROP 1 LAST PATH I219
J 0
(-3202 3025);
DISPLAY 0.872340 (-3202 3025);
PAINT GREEN (-3202 3025);
DISPLAY INVISIBLE (-3202 3025);
FORCEADD SCONN288_DDR506112002KQ..1
(-6800 3650);
FORCEPROP 1 LAST LOCATION J37
J 0
(-7250 5725);
DISPLAY 0.468085 (-7250 5725);
PAINT SKYBLUE (-7250 5725);
FORCEPROP 0 LAST $SEC 1
J 0
(-7250 5875);
DISPLAY 0.680851 (-7250 5875);
PAINT MONO (-7250 5875);
DISPLAY INVISIBLE (-7250 5875);
FORCEPROP 2 LAST CDS_SEC 1
J 0
(-7250 5875);
DISPLAY 1.021277 (-7250 5875);
DISPLAY INVISIBLE (-7250 5875);
FORCEPROP 0 LASTPIN (-7400 3050) $PN 62
J 2
(-7410 3060);
DISPLAY 0.680851 (-7410 3060);
PAINT MONO (-7410 3060);
FORCEPROP 0 LASTPIN (-7400 5100) $PN 66
J 2
(-7410 5110);
DISPLAY 0.680851 (-7410 5110);
PAINT MONO (-7410 5110);
FORCEPROP 0 LASTPIN (-7400 4700) $PN 76
J 2
(-7410 4710);
DISPLAY 0.680851 (-7410 4710);
PAINT MONO (-7410 4710);
FORCEPROP 0 LASTPIN (-7400 5150) $PN 211
J 2
(-7410 5160);
DISPLAY 0.680851 (-7410 5160);
PAINT MONO (-7410 5160);
FORCEPROP 0 LASTPIN (-7400 4750) $PN 221
J 2
(-7410 4760);
DISPLAY 0.680851 (-7410 4760);
PAINT MONO (-7410 4760);
FORCEPROP 0 LASTPIN (-7400 5200) $PN 68
J 2
(-7410 5210);
DISPLAY 0.680851 (-7410 5210);
PAINT MONO (-7410 5210);
FORCEPROP 0 LASTPIN (-7400 4800) $PN 78
J 2
(-7410 4810);
DISPLAY 0.680851 (-7410 4810);
PAINT MONO (-7410 4810);
FORCEPROP 0 LASTPIN (-7400 5250) $PN 213
J 2
(-7410 5260);
DISPLAY 0.680851 (-7410 5260);
PAINT MONO (-7410 5260);
FORCEPROP 0 LASTPIN (-7400 4850) $PN 223
J 2
(-7410 4860);
DISPLAY 0.680851 (-7410 4860);
PAINT MONO (-7410 4860);
FORCEPROP 0 LASTPIN (-7400 5300) $PN 70
J 2
(-7410 5310);
DISPLAY 0.680851 (-7410 5310);
PAINT MONO (-7410 5310);
FORCEPROP 0 LASTPIN (-7400 4900) $PN 80
J 2
(-7410 4910);
DISPLAY 0.680851 (-7410 4910);
PAINT MONO (-7410 4910);
FORCEPROP 0 LASTPIN (-7400 5350) $PN 215
J 2
(-7410 5360);
DISPLAY 0.680851 (-7410 5360);
PAINT MONO (-7410 5360);
FORCEPROP 0 LASTPIN (-7400 4950) $PN 225
J 2
(-7410 4960);
DISPLAY 0.680851 (-7410 4960);
PAINT MONO (-7410 4960);
FORCEPROP 0 LASTPIN (-7400 5400) $PN 72
J 2
(-7410 5410);
DISPLAY 0.680851 (-7410 5410);
PAINT MONO (-7410 5410);
FORCEPROP 0 LASTPIN (-7400 5000) $PN 82
J 2
(-7410 5010);
DISPLAY 0.680851 (-7410 5010);
PAINT MONO (-7410 5010);
FORCEPROP 0 LASTPIN (-7400 3650) $PN 51
J 2
(-7410 3660);
DISPLAY 0.680851 (-7410 3660);
PAINT MONO (-7410 3660);
FORCEPROP 0 LASTPIN (-7400 3200) $PN 96
J 2
(-7410 3210);
DISPLAY 0.680851 (-7410 3210);
PAINT MONO (-7410 3210);
FORCEPROP 0 LASTPIN (-7400 3700) $PN 53
J 2
(-7410 3710);
DISPLAY 0.680851 (-7410 3710);
PAINT MONO (-7410 3710);
FORCEPROP 0 LASTPIN (-7400 3250) $PN 98
J 2
(-7410 3260);
DISPLAY 0.680851 (-7410 3260);
PAINT MONO (-7410 3260);
FORCEPROP 0 LASTPIN (-7400 3750) $PN 196
J 2
(-7410 3760);
DISPLAY 0.680851 (-7410 3760);
PAINT MONO (-7410 3760);
FORCEPROP 0 LASTPIN (-7400 3300) $PN 241
J 2
(-7410 3310);
DISPLAY 0.680851 (-7410 3310);
PAINT MONO (-7410 3310);
FORCEPROP 0 LASTPIN (-7400 3800) $PN 198
J 2
(-7410 3810);
DISPLAY 0.680851 (-7410 3810);
PAINT MONO (-7410 3810);
FORCEPROP 0 LASTPIN (-7400 3350) $PN 243
J 2
(-7410 3360);
DISPLAY 0.680851 (-7410 3360);
PAINT MONO (-7410 3360);
FORCEPROP 0 LASTPIN (-7400 3850) $PN 58
J 2
(-7410 3860);
DISPLAY 0.680851 (-7410 3860);
PAINT MONO (-7410 3860);
FORCEPROP 0 LASTPIN (-7400 3400) $PN 89
J 2
(-7410 3410);
DISPLAY 0.680851 (-7410 3410);
PAINT MONO (-7410 3410);
FORCEPROP 0 LASTPIN (-7400 3900) $PN 60
J 2
(-7410 3910);
DISPLAY 0.680851 (-7410 3910);
PAINT MONO (-7410 3910);
FORCEPROP 0 LASTPIN (-7400 3450) $PN 91
J 2
(-7410 3460);
DISPLAY 0.680851 (-7410 3460);
PAINT MONO (-7410 3460);
FORCEPROP 0 LASTPIN (-7400 3950) $PN 203
J 2
(-7410 3960);
DISPLAY 0.680851 (-7410 3960);
PAINT MONO (-7410 3960);
FORCEPROP 0 LASTPIN (-7400 3500) $PN 234
J 2
(-7410 3510);
DISPLAY 0.680851 (-7410 3510);
PAINT MONO (-7410 3510);
FORCEPROP 0 LASTPIN (-7400 4000) $PN 205
J 2
(-7410 4010);
DISPLAY 0.680851 (-7410 4010);
PAINT MONO (-7410 4010);
FORCEPROP 0 LASTPIN (-7400 3550) $PN 236
J 2
(-7410 3560);
DISPLAY 0.680851 (-7410 3560);
PAINT MONO (-7410 3560);
FORCEPROP 0 LASTPIN (-7400 4100) $PN 218
J 2
(-7410 4110);
DISPLAY 0.680851 (-7410 4110);
PAINT MONO (-7410 4110);
FORCEPROP 0 LASTPIN (-7400 4150) $PN 217
J 2
(-7410 4160);
DISPLAY 0.680851 (-7410 4160);
PAINT MONO (-7410 4160);
FORCEPROP 0 LASTPIN (-7400 4400) $PN 64
J 2
(-7410 4410);
DISPLAY 0.680851 (-7410 4410);
PAINT MONO (-7410 4410);
FORCEPROP 0 LASTPIN (-7400 4250) $PN 84
J 2
(-7410 4260);
DISPLAY 0.680851 (-7410 4260);
PAINT MONO (-7410 4260);
FORCEPROP 0 LASTPIN (-7400 4450) $PN 209
J 2
(-7410 4460);
DISPLAY 0.680851 (-7410 4460);
PAINT MONO (-7410 4460);
FORCEPROP 0 LASTPIN (-7400 4300) $PN 229
J 2
(-7410 4310);
DISPLAY 0.680851 (-7410 4310);
PAINT MONO (-7410 4310);
FORCEPROP 0 LASTPIN (-6200 3850) $PN 7
J 0
(-6190 3860);
DISPLAY 0.680851 (-6190 3860);
PAINT MONO (-6190 3860);
FORCEPROP 0 LASTPIN (-6200 2200) $PN 100
J 0
(-6190 2210);
DISPLAY 0.680851 (-6190 2210);
PAINT MONO (-6190 2210);
FORCEPROP 0 LASTPIN (-6200 3900) $PN 9
J 0
(-6190 3910);
DISPLAY 0.680851 (-6190 3910);
PAINT MONO (-6190 3910);
FORCEPROP 0 LASTPIN (-6200 2250) $PN 102
J 0
(-6190 2260);
DISPLAY 0.680851 (-6190 2260);
PAINT MONO (-6190 2260);
FORCEPROP 0 LASTPIN (-6200 3950) $PN 152
J 0
(-6190 3960);
DISPLAY 0.680851 (-6190 3960);
PAINT MONO (-6190 3960);
FORCEPROP 0 LASTPIN (-6200 2300) $PN 245
J 0
(-6190 2310);
DISPLAY 0.680851 (-6190 2310);
PAINT MONO (-6190 2310);
FORCEPROP 0 LASTPIN (-6200 4000) $PN 154
J 0
(-6190 4010);
DISPLAY 0.680851 (-6190 4010);
PAINT MONO (-6190 4010);
FORCEPROP 0 LASTPIN (-6200 2350) $PN 247
J 0
(-6190 2360);
DISPLAY 0.680851 (-6190 2360);
PAINT MONO (-6190 2360);
FORCEPROP 0 LASTPIN (-6200 4050) $PN 14
J 0
(-6190 4060);
DISPLAY 0.680851 (-6190 4060);
PAINT MONO (-6190 4060);
FORCEPROP 0 LASTPIN (-6200 2400) $PN 107
J 0
(-6190 2410);
DISPLAY 0.680851 (-6190 2410);
PAINT MONO (-6190 2410);
FORCEPROP 0 LASTPIN (-6200 4100) $PN 16
J 0
(-6190 4110);
DISPLAY 0.680851 (-6190 4110);
PAINT MONO (-6190 4110);
FORCEPROP 0 LASTPIN (-6200 2450) $PN 109
J 0
(-6190 2460);
DISPLAY 0.680851 (-6190 2460);
PAINT MONO (-6190 2460);
FORCEPROP 0 LASTPIN (-6200 4150) $PN 159
J 0
(-6190 4160);
DISPLAY 0.680851 (-6190 4160);
PAINT MONO (-6190 4160);
FORCEPROP 0 LASTPIN (-6200 2500) $PN 252
J 0
(-6190 2510);
DISPLAY 0.680851 (-6190 2510);
PAINT MONO (-6190 2510);
FORCEPROP 0 LASTPIN (-6200 4200) $PN 161
J 0
(-6190 4210);
DISPLAY 0.680851 (-6190 4210);
PAINT MONO (-6190 4210);
FORCEPROP 0 LASTPIN (-6200 2550) $PN 254
J 0
(-6190 2560);
DISPLAY 0.680851 (-6190 2560);
PAINT MONO (-6190 2560);
FORCEPROP 0 LASTPIN (-6200 4250) $PN 18
J 0
(-6190 4260);
DISPLAY 0.680851 (-6190 4260);
PAINT MONO (-6190 4260);
FORCEPROP 0 LASTPIN (-6200 2600) $PN 111
J 0
(-6190 2610);
DISPLAY 0.680851 (-6190 2610);
PAINT MONO (-6190 2610);
FORCEPROP 0 LASTPIN (-6200 4300) $PN 20
J 0
(-6190 4310);
DISPLAY 0.680851 (-6190 4310);
PAINT MONO (-6190 4310);
FORCEPROP 0 LASTPIN (-6200 2650) $PN 113
J 0
(-6190 2660);
DISPLAY 0.680851 (-6190 2660);
PAINT MONO (-6190 2660);
FORCEPROP 0 LASTPIN (-6200 4350) $PN 163
J 0
(-6190 4360);
DISPLAY 0.680851 (-6190 4360);
PAINT MONO (-6190 4360);
FORCEPROP 0 LASTPIN (-6200 2700) $PN 256
J 0
(-6190 2710);
DISPLAY 0.680851 (-6190 2710);
PAINT MONO (-6190 2710);
FORCEPROP 0 LASTPIN (-6200 4400) $PN 165
J 0
(-6190 4410);
DISPLAY 0.680851 (-6190 4410);
PAINT MONO (-6190 4410);
FORCEPROP 0 LASTPIN (-6200 2750) $PN 258
J 0
(-6190 2760);
DISPLAY 0.680851 (-6190 2760);
PAINT MONO (-6190 2760);
FORCEPROP 0 LASTPIN (-6200 4450) $PN 25
J 0
(-6190 4460);
DISPLAY 0.680851 (-6190 4460);
PAINT MONO (-6190 4460);
FORCEPROP 0 LASTPIN (-6200 2800) $PN 118
J 0
(-6190 2810);
DISPLAY 0.680851 (-6190 2810);
PAINT MONO (-6190 2810);
FORCEPROP 0 LASTPIN (-6200 4500) $PN 27
J 0
(-6190 4510);
DISPLAY 0.680851 (-6190 4510);
PAINT MONO (-6190 4510);
FORCEPROP 0 LASTPIN (-6200 2850) $PN 120
J 0
(-6190 2860);
DISPLAY 0.680851 (-6190 2860);
PAINT MONO (-6190 2860);
FORCEPROP 0 LASTPIN (-6200 4550) $PN 170
J 0
(-6190 4560);
DISPLAY 0.680851 (-6190 4560);
PAINT MONO (-6190 4560);
FORCEPROP 0 LASTPIN (-6200 2900) $PN 263
J 0
(-6190 2910);
DISPLAY 0.680851 (-6190 2910);
PAINT MONO (-6190 2910);
FORCEPROP 0 LASTPIN (-6200 4600) $PN 172
J 0
(-6190 4610);
DISPLAY 0.680851 (-6190 4610);
PAINT MONO (-6190 4610);
FORCEPROP 0 LASTPIN (-6200 2950) $PN 265
J 0
(-6190 2960);
DISPLAY 0.680851 (-6190 2960);
PAINT MONO (-6190 2960);
FORCEPROP 0 LASTPIN (-6200 4650) $PN 29
J 0
(-6190 4660);
DISPLAY 0.680851 (-6190 4660);
PAINT MONO (-6190 4660);
FORCEPROP 0 LASTPIN (-6200 3000) $PN 122
J 0
(-6190 3010);
DISPLAY 0.680851 (-6190 3010);
PAINT MONO (-6190 3010);
FORCEPROP 0 LASTPIN (-6200 4700) $PN 31
J 0
(-6190 4710);
DISPLAY 0.680851 (-6190 4710);
PAINT MONO (-6190 4710);
FORCEPROP 0 LASTPIN (-6200 3050) $PN 124
J 0
(-6190 3060);
DISPLAY 0.680851 (-6190 3060);
PAINT MONO (-6190 3060);
FORCEPROP 0 LASTPIN (-6200 4750) $PN 174
J 0
(-6190 4760);
DISPLAY 0.680851 (-6190 4760);
PAINT MONO (-6190 4760);
FORCEPROP 0 LASTPIN (-6200 3100) $PN 267
J 0
(-6190 3110);
DISPLAY 0.680851 (-6190 3110);
PAINT MONO (-6190 3110);
FORCEPROP 0 LASTPIN (-6200 4800) $PN 176
J 0
(-6190 4810);
DISPLAY 0.680851 (-6190 4810);
PAINT MONO (-6190 4810);
FORCEPROP 0 LASTPIN (-6200 3150) $PN 269
J 0
(-6190 3160);
DISPLAY 0.680851 (-6190 3160);
PAINT MONO (-6190 3160);
FORCEPROP 0 LASTPIN (-6200 4850) $PN 36
J 0
(-6190 4860);
DISPLAY 0.680851 (-6190 4860);
PAINT MONO (-6190 4860);
FORCEPROP 0 LASTPIN (-6200 3200) $PN 129
J 0
(-6190 3210);
DISPLAY 0.680851 (-6190 3210);
PAINT MONO (-6190 3210);
FORCEPROP 0 LASTPIN (-6200 4900) $PN 38
J 0
(-6190 4910);
DISPLAY 0.680851 (-6190 4910);
PAINT MONO (-6190 4910);
FORCEPROP 0 LASTPIN (-6200 3250) $PN 131
J 0
(-6190 3260);
DISPLAY 0.680851 (-6190 3260);
PAINT MONO (-6190 3260);
FORCEPROP 0 LASTPIN (-6200 4950) $PN 181
J 0
(-6190 4960);
DISPLAY 0.680851 (-6190 4960);
PAINT MONO (-6190 4960);
FORCEPROP 0 LASTPIN (-6200 3300) $PN 274
J 0
(-6190 3310);
DISPLAY 0.680851 (-6190 3310);
PAINT MONO (-6190 3310);
FORCEPROP 0 LASTPIN (-6200 5000) $PN 183
J 0
(-6190 5010);
DISPLAY 0.680851 (-6190 5010);
PAINT MONO (-6190 5010);
FORCEPROP 0 LASTPIN (-6200 3350) $PN 276
J 0
(-6190 3360);
DISPLAY 0.680851 (-6190 3360);
PAINT MONO (-6190 3360);
FORCEPROP 0 LASTPIN (-6200 5050) $PN 40
J 0
(-6190 5060);
DISPLAY 0.680851 (-6190 5060);
PAINT MONO (-6190 5060);
FORCEPROP 0 LASTPIN (-6200 3400) $PN 133
J 0
(-6190 3410);
DISPLAY 0.680851 (-6190 3410);
PAINT MONO (-6190 3410);
FORCEPROP 0 LASTPIN (-6200 5100) $PN 42
J 0
(-6190 5110);
DISPLAY 0.680851 (-6190 5110);
PAINT MONO (-6190 5110);
FORCEPROP 0 LASTPIN (-6200 3450) $PN 135
J 0
(-6190 3460);
DISPLAY 0.680851 (-6190 3460);
PAINT MONO (-6190 3460);
FORCEPROP 0 LASTPIN (-6200 5150) $PN 185
J 0
(-6190 5160);
DISPLAY 0.680851 (-6190 5160);
PAINT MONO (-6190 5160);
FORCEPROP 0 LASTPIN (-6200 3500) $PN 278
J 0
(-6190 3510);
DISPLAY 0.680851 (-6190 3510);
PAINT MONO (-6190 3510);
FORCEPROP 0 LASTPIN (-6200 5200) $PN 187
J 0
(-6190 5210);
DISPLAY 0.680851 (-6190 5210);
PAINT MONO (-6190 5210);
FORCEPROP 0 LASTPIN (-6200 3550) $PN 280
J 0
(-6190 3560);
DISPLAY 0.680851 (-6190 3560);
PAINT MONO (-6190 3560);
FORCEPROP 0 LASTPIN (-6200 5250) $PN 47
J 0
(-6190 5260);
DISPLAY 0.680851 (-6190 5260);
PAINT MONO (-6190 5260);
FORCEPROP 0 LASTPIN (-6200 3600) $PN 140
J 0
(-6190 3610);
DISPLAY 0.680851 (-6190 3610);
PAINT MONO (-6190 3610);
FORCEPROP 0 LASTPIN (-6200 5300) $PN 49
J 0
(-6190 5310);
DISPLAY 0.680851 (-6190 5310);
PAINT MONO (-6190 5310);
FORCEPROP 0 LASTPIN (-6200 3650) $PN 142
J 0
(-6190 3660);
DISPLAY 0.680851 (-6190 3660);
PAINT MONO (-6190 3660);
FORCEPROP 0 LASTPIN (-6200 5350) $PN 192
J 0
(-6190 5360);
DISPLAY 0.680851 (-6190 5360);
PAINT MONO (-6190 5360);
FORCEPROP 0 LASTPIN (-6200 3700) $PN 285
J 0
(-6190 3710);
DISPLAY 0.680851 (-6190 3710);
PAINT MONO (-6190 3710);
FORCEPROP 0 LASTPIN (-6200 5400) $PN 194
J 0
(-6190 5410);
DISPLAY 0.680851 (-6190 5410);
PAINT MONO (-6190 5410);
FORCEPROP 0 LASTPIN (-6200 3750) $PN 287
J 0
(-6190 3760);
DISPLAY 0.680851 (-6190 3760);
PAINT MONO (-6190 3760);
FORCEPROP 0 LASTPIN (-7400 2900) $PN 148
J 2
(-7410 2910);
DISPLAY 0.680851 (-7410 2910);
PAINT MONO (-7410 2910);
FORCEPROP 0 LASTPIN (-7400 2800) $PN 4
J 2
(-7410 2810);
DISPLAY 0.680851 (-7410 2810);
PAINT MONO (-7410 2810);
FORCEPROP 0 LASTPIN (-7400 2850) $PN 5
J 2
(-7410 2860);
DISPLAY 0.680851 (-7410 2860);
PAINT MONO (-7410 2860);
FORCEPROP 0 LASTPIN (-7400 2000) $PN 86
J 2
(-7410 2010);
DISPLAY 0.680851 (-7410 2010);
PAINT MONO (-7410 2010);
FORCEPROP 0 LASTPIN (-7400 1950) $PN 87
J 2
(-7410 1960);
DISPLAY 0.680851 (-7410 1960);
PAINT MONO (-7410 1960);
FORCEPROP 0 LASTPIN (-7400 4600) $PN 74
J 2
(-7410 4610);
DISPLAY 0.680851 (-7410 4610);
PAINT MONO (-7410 4610);
FORCEPROP 0 LASTPIN (-7400 4550) $PN 227
J 2
(-7410 4560);
DISPLAY 0.680851 (-7410 4560);
PAINT MONO (-7410 4560);
FORCEPROP 0 LASTPIN (-7400 2550) $PN 147
J 2
(-7410 2560);
DISPLAY 0.680851 (-7410 2560);
PAINT MONO (-7410 2560);
FORCEPROP 0 LASTPIN (-7400 3100) $PN 207
J 2
(-7410 3110);
DISPLAY 0.680851 (-7410 3110);
PAINT MONO (-7410 3110);
FORCEPROP 0 LASTPIN (-7400 2150) $PN 2
J 2
(-7410 2160);
DISPLAY 0.680851 (-7410 2160);
PAINT MONO (-7410 2160);
FORCEPROP 0 LASTPIN (-7400 2200) $PN 144
J 2
(-7410 2210);
DISPLAY 0.680851 (-7410 2210);
PAINT MONO (-7410 2210);
FORCEPROP 0 LASTPIN (-7400 2250) $PN 149
J 2
(-7410 2260);
DISPLAY 0.680851 (-7410 2260);
PAINT MONO (-7410 2260);
FORCEPROP 0 LASTPIN (-7400 2300) $PN 150
J 2
(-7410 2310);
DISPLAY 0.680851 (-7410 2310);
PAINT MONO (-7410 2310);
FORCEPROP 0 LASTPIN (-7400 2350) $PN 220
J 2
(-7410 2360);
DISPLAY 0.680851 (-7410 2360);
PAINT MONO (-7410 2360);
FORCEPROP 0 LASTPIN (-7400 2400) $PN 231
J 2
(-7410 2410);
DISPLAY 0.680851 (-7410 2410);
PAINT MONO (-7410 2410);
FORCEPROP 0 LASTPIN (-7400 2450) $PN 232
J 2
(-7410 2460);
DISPLAY 0.680851 (-7410 2460);
PAINT MONO (-7410 2460);
FORCEPROP 0 LASTPIN (-7400 2950) $PN 3
J 2
(-7410 2960);
DISPLAY 0.680851 (-7410 2960);
PAINT MONO (-7410 2960);
FORCEPROP 1 LAST MATERIAL IO
J 0
(-7250 5575);
DISPLAY 0.468085 (-7250 5575);
PAINT SKYBLUE (-7250 5575);
FORCEPROP 2 LAST PART_TYPE SMLF
J 0
(-7250 5825);
DISPLAY 1.021277 (-7250 5825);
FORCEPROP 2 LAST VALUE SCONN288_DDR506112002KQ
J 0
(-7250 5775);
DISPLAY 0.489362 (-7250 5775);
PAINT SKYBLUE (-7250 5775);
FORCEPROP 2 LAST CDS_LIB pure_quanta
J 0
(-6800 3650);
DISPLAY INVISIBLE (-6800 3650);
FORCEPROP 1 LAST NEEDS_NO_SIZE TRUE
J 0
(-6800 3650);
DISPLAY 0.723404 (-6800 3650);
PAINT GREEN (-6800 3650);
DISPLAY INVISIBLE (-6800 3650);
FORCEPROP 1 LAST CDS_LMAN_SYM_OUTLINE -450,1900,450,-1850
J 0
(-6800 3650);
DISPLAY 0.468085 (-6800 3650);
PAINT GREEN (-6800 3650);
DISPLAY INVISIBLE (-6800 3650);
FORCEPROP 1 LAST PATH I22
J 0
(-6800 3650);
DISPLAY 0.723404 (-6800 3650);
PAINT GREEN (-6800 3650);
DISPLAY INVISIBLE (-6800 3650);
FORCEPROP 1 LAST PART_NUMBER DFHST8FS479
J 0
(-7250 5650);
DISPLAY 0.468085 (-7250 5650);
PAINT SKYBLUE (-7250 5650);
DISPLAY INVISIBLE (-7250 5650);
FORCEADD TAP..1
(-3200 2925);
FORCEPROP 3 LASTPIN (-3250 2925) SIG_NAME M_L_CPU1_SB_DQS_DN<6>
J 0
(-3240 2935);
DISPLAY 0.659574 (-3240 2935);
PAINT MONO (-3240 2935);
DISPLAY INVISIBLE (-3240 2935);
FORCEPROP 1 LASTPIN (-3250 2925) BN 6
J 0
(-3262 2933);
DISPLAY 0.489362 (-3262 2933);
PAINT GREEN (-3262 2933);
FORCEPROP 2 LAST CDS_LIB mstr_standard
J 0
(-3200 2925);
DISPLAY 0.723404 (-3200 2925);
PAINT MONO (-3200 2925);
DISPLAY INVISIBLE (-3200 2925);
FORCEPROP 1 LAST BODY_TYPE PLUMBING
J 0
(-3200 2975);
DISPLAY 0.872340 (-3200 2975);
PAINT GREEN (-3200 2975);
DISPLAY INVISIBLE (-3200 2975);
FORCEPROP 1 LAST HDL_TAP TRUE
J 0
(-2875 2800);
DISPLAY 0.872340 (-2875 2800);
DISPLAY INVISIBLE (-2875 2800);
FORCEPROP 1 LAST PATH I220
J 0
(-3202 2925);
DISPLAY 0.872340 (-3202 2925);
PAINT GREEN (-3202 2925);
DISPLAY INVISIBLE (-3202 2925);
FORCEADD TAP..1
(-3200 2725);
FORCEPROP 3 LASTPIN (-3250 2725) SIG_NAME M_L_CPU1_SB_DQS_DN<4>
J 0
(-3240 2735);
DISPLAY 0.659574 (-3240 2735);
PAINT MONO (-3240 2735);
DISPLAY INVISIBLE (-3240 2735);
FORCEPROP 1 LASTPIN (-3250 2725) BN 4
J 0
(-3262 2733);
DISPLAY 0.489362 (-3262 2733);
PAINT GREEN (-3262 2733);
FORCEPROP 2 LAST CDS_LIB mstr_standard
J 0
(-3200 2725);
DISPLAY 0.723404 (-3200 2725);
PAINT MONO (-3200 2725);
DISPLAY INVISIBLE (-3200 2725);
FORCEPROP 1 LAST BODY_TYPE PLUMBING
J 0
(-3200 2775);
DISPLAY 0.872340 (-3200 2775);
PAINT GREEN (-3200 2775);
DISPLAY INVISIBLE (-3200 2775);
FORCEPROP 1 LAST HDL_TAP TRUE
J 0
(-2875 2600);
DISPLAY 0.872340 (-2875 2600);
DISPLAY INVISIBLE (-2875 2600);
FORCEPROP 1 LAST PATH I221
J 0
(-3202 2725);
DISPLAY 0.872340 (-3202 2725);
PAINT GREEN (-3202 2725);
DISPLAY INVISIBLE (-3202 2725);
FORCEADD TAP..1
(-3200 2825);
FORCEPROP 3 LASTPIN (-3250 2825) SIG_NAME M_L_CPU1_SB_DQS_DN<5>
J 0
(-3240 2835);
DISPLAY 0.659574 (-3240 2835);
PAINT MONO (-3240 2835);
DISPLAY INVISIBLE (-3240 2835);
FORCEPROP 1 LASTPIN (-3250 2825) BN 5
J 0
(-3262 2833);
DISPLAY 0.489362 (-3262 2833);
PAINT GREEN (-3262 2833);
FORCEPROP 2 LAST CDS_LIB mstr_standard
J 0
(-3200 2825);
DISPLAY 0.723404 (-3200 2825);
PAINT MONO (-3200 2825);
DISPLAY INVISIBLE (-3200 2825);
FORCEPROP 1 LAST BODY_TYPE PLUMBING
J 0
(-3200 2875);
DISPLAY 0.872340 (-3200 2875);
PAINT GREEN (-3200 2875);
DISPLAY INVISIBLE (-3200 2875);
FORCEPROP 1 LAST HDL_TAP TRUE
J 0
(-2875 2700);
DISPLAY 0.872340 (-2875 2700);
DISPLAY INVISIBLE (-2875 2700);
FORCEPROP 1 LAST PATH I222
J 0
(-3202 2825);
DISPLAY 0.872340 (-3202 2825);
PAINT GREEN (-3202 2825);
DISPLAY INVISIBLE (-3202 2825);
FORCEADD TAP..1
(-3200 2625);
FORCEPROP 3 LASTPIN (-3250 2625) SIG_NAME M_L_CPU1_SB_DQS_DN<3>
J 0
(-3240 2635);
DISPLAY 0.659574 (-3240 2635);
PAINT MONO (-3240 2635);
DISPLAY INVISIBLE (-3240 2635);
FORCEPROP 1 LASTPIN (-3250 2625) BN 3
J 0
(-3262 2633);
DISPLAY 0.489362 (-3262 2633);
PAINT GREEN (-3262 2633);
FORCEPROP 2 LAST CDS_LIB mstr_standard
J 0
(-3200 2625);
DISPLAY 0.723404 (-3200 2625);
PAINT MONO (-3200 2625);
DISPLAY INVISIBLE (-3200 2625);
FORCEPROP 1 LAST BODY_TYPE PLUMBING
J 0
(-3200 2675);
DISPLAY 0.872340 (-3200 2675);
PAINT GREEN (-3200 2675);
DISPLAY INVISIBLE (-3200 2675);
FORCEPROP 1 LAST HDL_TAP TRUE
J 0
(-2875 2500);
DISPLAY 0.872340 (-2875 2500);
DISPLAY INVISIBLE (-2875 2500);
FORCEPROP 1 LAST PATH I223
J 0
(-3202 2625);
DISPLAY 0.872340 (-3202 2625);
PAINT GREEN (-3202 2625);
DISPLAY INVISIBLE (-3202 2625);
FORCEADD TAP..1
(-3200 2525);
FORCEPROP 3 LASTPIN (-3250 2525) SIG_NAME M_L_CPU1_SB_DQS_DN<2>
J 0
(-3240 2535);
DISPLAY 0.659574 (-3240 2535);
PAINT MONO (-3240 2535);
DISPLAY INVISIBLE (-3240 2535);
FORCEPROP 1 LASTPIN (-3250 2525) BN 2
J 0
(-3262 2533);
DISPLAY 0.489362 (-3262 2533);
PAINT GREEN (-3262 2533);
FORCEPROP 2 LAST CDS_LIB mstr_standard
J 0
(-3200 2525);
DISPLAY 0.723404 (-3200 2525);
PAINT MONO (-3200 2525);
DISPLAY INVISIBLE (-3200 2525);
FORCEPROP 1 LAST BODY_TYPE PLUMBING
J 0
(-3200 2575);
DISPLAY 0.872340 (-3200 2575);
PAINT GREEN (-3200 2575);
DISPLAY INVISIBLE (-3200 2575);
FORCEPROP 1 LAST HDL_TAP TRUE
J 0
(-2875 2400);
DISPLAY 0.872340 (-2875 2400);
DISPLAY INVISIBLE (-2875 2400);
FORCEPROP 1 LAST PATH I224
J 0
(-3202 2525);
DISPLAY 0.872340 (-3202 2525);
PAINT GREEN (-3202 2525);
DISPLAY INVISIBLE (-3202 2525);
FORCEADD TAP..1
(-3200 2425);
FORCEPROP 3 LASTPIN (-3250 2425) SIG_NAME M_L_CPU1_SB_DQS_DN<1>
J 0
(-3240 2435);
DISPLAY 0.659574 (-3240 2435);
PAINT MONO (-3240 2435);
DISPLAY INVISIBLE (-3240 2435);
FORCEPROP 1 LASTPIN (-3250 2425) BN 1
J 0
(-3262 2433);
DISPLAY 0.489362 (-3262 2433);
PAINT GREEN (-3262 2433);
FORCEPROP 2 LAST CDS_LIB mstr_standard
J 0
(-3200 2425);
DISPLAY 0.723404 (-3200 2425);
PAINT MONO (-3200 2425);
DISPLAY INVISIBLE (-3200 2425);
FORCEPROP 1 LAST BODY_TYPE PLUMBING
J 0
(-3200 2475);
DISPLAY 0.872340 (-3200 2475);
PAINT GREEN (-3200 2475);
DISPLAY INVISIBLE (-3200 2475);
FORCEPROP 1 LAST HDL_TAP TRUE
J 0
(-2875 2300);
DISPLAY 0.872340 (-2875 2300);
DISPLAY INVISIBLE (-2875 2300);
FORCEPROP 1 LAST PATH I225
J 0
(-3202 2425);
DISPLAY 0.872340 (-3202 2425);
PAINT GREEN (-3202 2425);
DISPLAY INVISIBLE (-3202 2425);
FORCEADD TAP..1
(-3200 2325);
FORCEPROP 3 LASTPIN (-3250 2325) SIG_NAME M_L_CPU1_SB_DQS_DN<0>
J 0
(-3240 2335);
DISPLAY 0.659574 (-3240 2335);
PAINT MONO (-3240 2335);
DISPLAY INVISIBLE (-3240 2335);
FORCEPROP 1 LASTPIN (-3250 2325) BN 0
J 0
(-3262 2333);
DISPLAY 0.489362 (-3262 2333);
PAINT GREEN (-3262 2333);
FORCEPROP 2 LAST CDS_LIB mstr_standard
J 0
(-3200 2325);
DISPLAY 0.723404 (-3200 2325);
PAINT MONO (-3200 2325);
DISPLAY INVISIBLE (-3200 2325);
FORCEPROP 1 LAST BODY_TYPE PLUMBING
J 0
(-3200 2375);
DISPLAY 0.872340 (-3200 2375);
PAINT GREEN (-3200 2375);
DISPLAY INVISIBLE (-3200 2375);
FORCEPROP 1 LAST HDL_TAP TRUE
J 0
(-2875 2200);
DISPLAY 0.872340 (-2875 2200);
DISPLAY INVISIBLE (-2875 2200);
FORCEPROP 1 LAST PATH I226
J 0
(-3202 2325);
DISPLAY 0.872340 (-3202 2325);
PAINT GREEN (-3202 2325);
DISPLAY INVISIBLE (-3202 2325);
FORCEADD TAP..1
(-3400 2975);
FORCEPROP 3 LASTPIN (-3450 2975) SIG_NAME M_L_CPU1_SB_DQS_DP<6>
J 0
(-3440 2985);
DISPLAY 0.659574 (-3440 2985);
PAINT MONO (-3440 2985);
DISPLAY INVISIBLE (-3440 2985);
FORCEPROP 1 LASTPIN (-3450 2975) BN 6
J 0
(-3462 2983);
DISPLAY 0.489362 (-3462 2983);
PAINT GREEN (-3462 2983);
FORCEPROP 2 LAST CDS_LIB mstr_standard
J 0
(-3400 2975);
DISPLAY 0.723404 (-3400 2975);
PAINT MONO (-3400 2975);
DISPLAY INVISIBLE (-3400 2975);
FORCEPROP 1 LAST BODY_TYPE PLUMBING
J 0
(-3400 3025);
DISPLAY 0.872340 (-3400 3025);
PAINT GREEN (-3400 3025);
DISPLAY INVISIBLE (-3400 3025);
FORCEPROP 1 LAST HDL_TAP TRUE
J 0
(-3075 2850);
DISPLAY 0.872340 (-3075 2850);
DISPLAY INVISIBLE (-3075 2850);
FORCEPROP 1 LAST PATH I227
J 0
(-3402 2975);
DISPLAY 0.872340 (-3402 2975);
PAINT GREEN (-3402 2975);
DISPLAY INVISIBLE (-3402 2975);
FORCEADD TAP..1
(-3400 3075);
FORCEPROP 3 LASTPIN (-3450 3075) SIG_NAME M_L_CPU1_SB_DQS_DP<7>
J 0
(-3440 3085);
DISPLAY 0.659574 (-3440 3085);
PAINT MONO (-3440 3085);
DISPLAY INVISIBLE (-3440 3085);
FORCEPROP 1 LASTPIN (-3450 3075) BN 7
J 0
(-3462 3083);
DISPLAY 0.489362 (-3462 3083);
PAINT GREEN (-3462 3083);
FORCEPROP 2 LAST CDS_LIB mstr_standard
J 0
(-3400 3075);
DISPLAY 0.723404 (-3400 3075);
PAINT MONO (-3400 3075);
DISPLAY INVISIBLE (-3400 3075);
FORCEPROP 1 LAST BODY_TYPE PLUMBING
J 0
(-3400 3125);
DISPLAY 0.872340 (-3400 3125);
PAINT GREEN (-3400 3125);
DISPLAY INVISIBLE (-3400 3125);
FORCEPROP 1 LAST HDL_TAP TRUE
J 0
(-3075 2950);
DISPLAY 0.872340 (-3075 2950);
DISPLAY INVISIBLE (-3075 2950);
FORCEPROP 1 LAST PATH I228
J 0
(-3402 3075);
DISPLAY 0.872340 (-3402 3075);
PAINT GREEN (-3402 3075);
DISPLAY INVISIBLE (-3402 3075);
FORCEADD TAP..1
(-3400 2875);
FORCEPROP 3 LASTPIN (-3450 2875) SIG_NAME M_L_CPU1_SB_DQS_DP<5>
J 0
(-3440 2885);
DISPLAY 0.659574 (-3440 2885);
PAINT MONO (-3440 2885);
DISPLAY INVISIBLE (-3440 2885);
FORCEPROP 1 LASTPIN (-3450 2875) BN 5
J 0
(-3462 2883);
DISPLAY 0.489362 (-3462 2883);
PAINT GREEN (-3462 2883);
FORCEPROP 2 LAST CDS_LIB mstr_standard
J 0
(-3400 2875);
DISPLAY 0.723404 (-3400 2875);
PAINT MONO (-3400 2875);
DISPLAY INVISIBLE (-3400 2875);
FORCEPROP 1 LAST BODY_TYPE PLUMBING
J 0
(-3400 2925);
DISPLAY 0.872340 (-3400 2925);
PAINT GREEN (-3400 2925);
DISPLAY INVISIBLE (-3400 2925);
FORCEPROP 1 LAST HDL_TAP TRUE
J 0
(-3075 2750);
DISPLAY 0.872340 (-3075 2750);
DISPLAY INVISIBLE (-3075 2750);
FORCEPROP 1 LAST PATH I229
J 0
(-3402 2875);
DISPLAY 0.872340 (-3402 2875);
PAINT GREEN (-3402 2875);
DISPLAY INVISIBLE (-3402 2875);
FORCEADD TAP..1
R 2
(-7650 3200);
FORCEPROP 3 LASTPIN (-7600 3200) SIG_NAME M_L_CPU1_SB_CB<0>
J 0
(-7590 3210);
DISPLAY 0.659574 (-7590 3210);
PAINT MONO (-7590 3210);
DISPLAY INVISIBLE (-7590 3210);
FORCEPROP 1 LASTPIN (-7600 3200) BN 0
J 2
(-7588 3208);
DISPLAY 0.489362 (-7588 3208);
PAINT GREEN (-7588 3208);
FORCEPROP 2 LAST CDS_LIB mstr_standard
J 0
(-7650 3200);
DISPLAY 0.723404 (-7650 3200);
PAINT MONO (-7650 3200);
DISPLAY INVISIBLE (-7650 3200);
FORCEPROP 1 LAST BODY_TYPE PLUMBING
J 2
(-7650 3250);
DISPLAY 0.872340 (-7650 3250);
PAINT GREEN (-7650 3250);
DISPLAY INVISIBLE (-7650 3250);
FORCEPROP 1 LAST HDL_TAP TRUE
J 2
(-7975 3075);
DISPLAY 0.872340 (-7975 3075);
DISPLAY INVISIBLE (-7975 3075);
FORCEPROP 1 LAST PATH I23
J 2
(-7648 3200);
DISPLAY 0.872340 (-7648 3200);
PAINT GREEN (-7648 3200);
DISPLAY INVISIBLE (-7648 3200);
FORCEADD TAP..1
(-3400 2775);
FORCEPROP 3 LASTPIN (-3450 2775) SIG_NAME M_L_CPU1_SB_DQS_DP<4>
J 0
(-3440 2785);
DISPLAY 0.659574 (-3440 2785);
PAINT MONO (-3440 2785);
DISPLAY INVISIBLE (-3440 2785);
FORCEPROP 1 LASTPIN (-3450 2775) BN 4
J 0
(-3462 2783);
DISPLAY 0.489362 (-3462 2783);
PAINT GREEN (-3462 2783);
FORCEPROP 2 LAST CDS_LIB mstr_standard
J 0
(-3400 2775);
DISPLAY 0.723404 (-3400 2775);
PAINT MONO (-3400 2775);
DISPLAY INVISIBLE (-3400 2775);
FORCEPROP 1 LAST BODY_TYPE PLUMBING
J 0
(-3400 2825);
DISPLAY 0.872340 (-3400 2825);
PAINT GREEN (-3400 2825);
DISPLAY INVISIBLE (-3400 2825);
FORCEPROP 1 LAST HDL_TAP TRUE
J 0
(-3075 2650);
DISPLAY 0.872340 (-3075 2650);
DISPLAY INVISIBLE (-3075 2650);
FORCEPROP 1 LAST PATH I230
J 0
(-3402 2775);
DISPLAY 0.872340 (-3402 2775);
PAINT GREEN (-3402 2775);
DISPLAY INVISIBLE (-3402 2775);
FORCEADD TAP..1
(-3400 2675);
FORCEPROP 3 LASTPIN (-3450 2675) SIG_NAME M_L_CPU1_SB_DQS_DP<3>
J 0
(-3440 2685);
DISPLAY 0.659574 (-3440 2685);
PAINT MONO (-3440 2685);
DISPLAY INVISIBLE (-3440 2685);
FORCEPROP 1 LASTPIN (-3450 2675) BN 3
J 0
(-3462 2683);
DISPLAY 0.489362 (-3462 2683);
PAINT GREEN (-3462 2683);
FORCEPROP 2 LAST CDS_LIB mstr_standard
J 0
(-3400 2675);
DISPLAY 0.723404 (-3400 2675);
PAINT MONO (-3400 2675);
DISPLAY INVISIBLE (-3400 2675);
FORCEPROP 1 LAST BODY_TYPE PLUMBING
J 0
(-3400 2725);
DISPLAY 0.872340 (-3400 2725);
PAINT GREEN (-3400 2725);
DISPLAY INVISIBLE (-3400 2725);
FORCEPROP 1 LAST HDL_TAP TRUE
J 0
(-3075 2550);
DISPLAY 0.872340 (-3075 2550);
DISPLAY INVISIBLE (-3075 2550);
FORCEPROP 1 LAST PATH I231
J 0
(-3402 2675);
DISPLAY 0.872340 (-3402 2675);
PAINT GREEN (-3402 2675);
DISPLAY INVISIBLE (-3402 2675);
FORCEADD TAP..1
(-3400 2375);
FORCEPROP 3 LASTPIN (-3450 2375) SIG_NAME M_L_CPU1_SB_DQS_DP<0>
J 0
(-3440 2385);
DISPLAY 0.659574 (-3440 2385);
PAINT MONO (-3440 2385);
DISPLAY INVISIBLE (-3440 2385);
FORCEPROP 1 LASTPIN (-3450 2375) BN 0
J 0
(-3462 2383);
DISPLAY 0.489362 (-3462 2383);
PAINT GREEN (-3462 2383);
FORCEPROP 2 LAST CDS_LIB mstr_standard
J 0
(-3400 2375);
DISPLAY 0.723404 (-3400 2375);
PAINT MONO (-3400 2375);
DISPLAY INVISIBLE (-3400 2375);
FORCEPROP 1 LAST BODY_TYPE PLUMBING
J 0
(-3400 2425);
DISPLAY 0.872340 (-3400 2425);
PAINT GREEN (-3400 2425);
DISPLAY INVISIBLE (-3400 2425);
FORCEPROP 1 LAST HDL_TAP TRUE
J 0
(-3075 2250);
DISPLAY 0.872340 (-3075 2250);
DISPLAY INVISIBLE (-3075 2250);
FORCEPROP 1 LAST PATH I232
J 0
(-3402 2375);
DISPLAY 0.872340 (-3402 2375);
PAINT GREEN (-3402 2375);
DISPLAY INVISIBLE (-3402 2375);
FORCEADD TAP..1
(-3400 2575);
FORCEPROP 3 LASTPIN (-3450 2575) SIG_NAME M_L_CPU1_SB_DQS_DP<2>
J 0
(-3440 2585);
DISPLAY 0.659574 (-3440 2585);
PAINT MONO (-3440 2585);
DISPLAY INVISIBLE (-3440 2585);
FORCEPROP 1 LASTPIN (-3450 2575) BN 2
J 0
(-3462 2583);
DISPLAY 0.489362 (-3462 2583);
PAINT GREEN (-3462 2583);
FORCEPROP 2 LAST CDS_LIB mstr_standard
J 0
(-3400 2575);
DISPLAY 0.723404 (-3400 2575);
PAINT MONO (-3400 2575);
DISPLAY INVISIBLE (-3400 2575);
FORCEPROP 1 LAST BODY_TYPE PLUMBING
J 0
(-3400 2625);
DISPLAY 0.872340 (-3400 2625);
PAINT GREEN (-3400 2625);
DISPLAY INVISIBLE (-3400 2625);
FORCEPROP 1 LAST HDL_TAP TRUE
J 0
(-3075 2450);
DISPLAY 0.872340 (-3075 2450);
DISPLAY INVISIBLE (-3075 2450);
FORCEPROP 1 LAST PATH I233
J 0
(-3402 2575);
DISPLAY 0.872340 (-3402 2575);
PAINT GREEN (-3402 2575);
DISPLAY INVISIBLE (-3402 2575);
FORCEADD TAP..1
(-3400 2475);
FORCEPROP 3 LASTPIN (-3450 2475) SIG_NAME M_L_CPU1_SB_DQS_DP<1>
J 0
(-3440 2485);
DISPLAY 0.659574 (-3440 2485);
PAINT MONO (-3440 2485);
DISPLAY INVISIBLE (-3440 2485);
FORCEPROP 1 LASTPIN (-3450 2475) BN 1
J 0
(-3462 2483);
DISPLAY 0.489362 (-3462 2483);
PAINT GREEN (-3462 2483);
FORCEPROP 2 LAST CDS_LIB mstr_standard
J 0
(-3400 2475);
DISPLAY 0.723404 (-3400 2475);
PAINT MONO (-3400 2475);
DISPLAY INVISIBLE (-3400 2475);
FORCEPROP 1 LAST BODY_TYPE PLUMBING
J 0
(-3400 2525);
DISPLAY 0.872340 (-3400 2525);
PAINT GREEN (-3400 2525);
DISPLAY INVISIBLE (-3400 2525);
FORCEPROP 1 LAST HDL_TAP TRUE
J 0
(-3075 2350);
DISPLAY 0.872340 (-3075 2350);
DISPLAY INVISIBLE (-3075 2350);
FORCEPROP 1 LAST PATH I234
J 0
(-3402 2475);
DISPLAY 0.872340 (-3402 2475);
PAINT GREEN (-3402 2475);
DISPLAY INVISIBLE (-3402 2475);
FORCEADD SCONN288_DDR506112002KQ..2
(-4350 3325);
FORCEPROP 1 LAST LOCATION J37
J 0
(-4950 4650);
DISPLAY 0.468085 (-4950 4650);
PAINT SKYBLUE (-4950 4650);
FORCEPROP 0 LAST $SEC 2
J 0
(-4800 4800);
DISPLAY 0.680851 (-4800 4800);
PAINT MONO (-4800 4800);
DISPLAY INVISIBLE (-4800 4800);
FORCEPROP 0 LAST CDS_SEC 2
J 0
(-4800 4800);
DISPLAY 1.021277 (-4800 4800);
DISPLAY INVISIBLE (-4800 4800);
FORCEPROP 0 LASTPIN (-3600 3375) $PN 12
J 0
(-3590 3385);
DISPLAY 0.680851 (-3590 3385);
PAINT MONO (-3590 3385);
FORCEPROP 0 LASTPIN (-3600 3425) $PN 11
J 0
(-3590 3435);
DISPLAY 0.680851 (-3590 3435);
PAINT MONO (-3590 3435);
FORCEPROP 0 LASTPIN (-3600 2325) $PN 105
J 0
(-3590 2335);
DISPLAY 0.680851 (-3590 2335);
PAINT MONO (-3590 2335);
FORCEPROP 0 LASTPIN (-3600 2375) $PN 104
J 0
(-3590 2385);
DISPLAY 0.680851 (-3590 2385);
PAINT MONO (-3590 2385);
FORCEPROP 0 LASTPIN (-3600 3475) $PN 23
J 0
(-3590 3485);
DISPLAY 0.680851 (-3590 3485);
PAINT MONO (-3590 3485);
FORCEPROP 0 LASTPIN (-3600 3525) $PN 22
J 0
(-3590 3535);
DISPLAY 0.680851 (-3590 3535);
PAINT MONO (-3590 3535);
FORCEPROP 0 LASTPIN (-3600 2425) $PN 116
J 0
(-3590 2435);
DISPLAY 0.680851 (-3590 2435);
PAINT MONO (-3590 2435);
FORCEPROP 0 LASTPIN (-3600 2475) $PN 115
J 0
(-3590 2485);
DISPLAY 0.680851 (-3590 2485);
PAINT MONO (-3590 2485);
FORCEPROP 0 LASTPIN (-3600 3575) $PN 34
J 0
(-3590 3585);
DISPLAY 0.680851 (-3590 3585);
PAINT MONO (-3590 3585);
FORCEPROP 0 LASTPIN (-3600 3625) $PN 33
J 0
(-3590 3635);
DISPLAY 0.680851 (-3590 3635);
PAINT MONO (-3590 3635);
FORCEPROP 0 LASTPIN (-3600 2525) $PN 127
J 0
(-3590 2535);
DISPLAY 0.680851 (-3590 2535);
PAINT MONO (-3590 2535);
FORCEPROP 0 LASTPIN (-3600 2575) $PN 126
J 0
(-3590 2585);
DISPLAY 0.680851 (-3590 2585);
PAINT MONO (-3590 2585);
FORCEPROP 0 LASTPIN (-3600 3675) $PN 45
J 0
(-3590 3685);
DISPLAY 0.680851 (-3590 3685);
PAINT MONO (-3590 3685);
FORCEPROP 0 LASTPIN (-3600 3725) $PN 44
J 0
(-3590 3735);
DISPLAY 0.680851 (-3590 3735);
PAINT MONO (-3590 3735);
FORCEPROP 0 LASTPIN (-3600 2625) $PN 138
J 0
(-3590 2635);
DISPLAY 0.680851 (-3590 2635);
PAINT MONO (-3590 2635);
FORCEPROP 0 LASTPIN (-3600 2675) $PN 137
J 0
(-3590 2685);
DISPLAY 0.680851 (-3590 2685);
PAINT MONO (-3590 2685);
FORCEPROP 0 LASTPIN (-3600 3775) $PN 56
J 0
(-3590 3785);
DISPLAY 0.680851 (-3590 3785);
PAINT MONO (-3590 3785);
FORCEPROP 0 LASTPIN (-3600 3825) $PN 55
J 0
(-3590 3835);
DISPLAY 0.680851 (-3590 3835);
PAINT MONO (-3590 3835);
FORCEPROP 0 LASTPIN (-3600 2725) $PN 238
J 0
(-3590 2735);
DISPLAY 0.680851 (-3590 2735);
PAINT MONO (-3590 2735);
FORCEPROP 0 LASTPIN (-3600 2775) $PN 239
J 0
(-3590 2785);
DISPLAY 0.680851 (-3590 2785);
PAINT MONO (-3590 2785);
FORCEPROP 0 LASTPIN (-3600 3875) $PN 156
J 0
(-3590 3885);
DISPLAY 0.680851 (-3590 3885);
PAINT MONO (-3590 3885);
FORCEPROP 0 LASTPIN (-3600 3925) $PN 157
J 0
(-3590 3935);
DISPLAY 0.680851 (-3590 3935);
PAINT MONO (-3590 3935);
FORCEPROP 0 LASTPIN (-3600 2825) $PN 249
J 0
(-3590 2835);
DISPLAY 0.680851 (-3590 2835);
PAINT MONO (-3590 2835);
FORCEPROP 0 LASTPIN (-3600 2875) $PN 250
J 0
(-3590 2885);
DISPLAY 0.680851 (-3590 2885);
PAINT MONO (-3590 2885);
FORCEPROP 0 LASTPIN (-3600 3975) $PN 167
J 0
(-3590 3985);
DISPLAY 0.680851 (-3590 3985);
PAINT MONO (-3590 3985);
FORCEPROP 0 LASTPIN (-3600 4025) $PN 168
J 0
(-3590 4035);
DISPLAY 0.680851 (-3590 4035);
PAINT MONO (-3590 4035);
FORCEPROP 0 LASTPIN (-3600 2925) $PN 260
J 0
(-3590 2935);
DISPLAY 0.680851 (-3590 2935);
PAINT MONO (-3590 2935);
FORCEPROP 0 LASTPIN (-3600 2975) $PN 261
J 0
(-3590 2985);
DISPLAY 0.680851 (-3590 2985);
PAINT MONO (-3590 2985);
FORCEPROP 0 LASTPIN (-3600 4075) $PN 178
J 0
(-3590 4085);
DISPLAY 0.680851 (-3590 4085);
PAINT MONO (-3590 4085);
FORCEPROP 0 LASTPIN (-3600 4125) $PN 179
J 0
(-3590 4135);
DISPLAY 0.680851 (-3590 4135);
PAINT MONO (-3590 4135);
FORCEPROP 0 LASTPIN (-3600 3025) $PN 271
J 0
(-3590 3035);
DISPLAY 0.680851 (-3590 3035);
PAINT MONO (-3590 3035);
FORCEPROP 0 LASTPIN (-3600 3075) $PN 272
J 0
(-3590 3085);
DISPLAY 0.680851 (-3590 3085);
PAINT MONO (-3590 3085);
FORCEPROP 0 LASTPIN (-3600 4175) $PN 189
J 0
(-3590 4185);
DISPLAY 0.680851 (-3590 4185);
PAINT MONO (-3590 4185);
FORCEPROP 0 LASTPIN (-3600 4225) $PN 190
J 0
(-3590 4235);
DISPLAY 0.680851 (-3590 4235);
PAINT MONO (-3590 4235);
FORCEPROP 0 LASTPIN (-3600 3125) $PN 282
J 0
(-3590 3135);
DISPLAY 0.680851 (-3590 3135);
PAINT MONO (-3590 3135);
FORCEPROP 0 LASTPIN (-3600 3175) $PN 283
J 0
(-3590 3185);
DISPLAY 0.680851 (-3590 3185);
PAINT MONO (-3590 3185);
FORCEPROP 0 LASTPIN (-3600 4275) $PN 200
J 0
(-3590 4285);
DISPLAY 0.680851 (-3590 4285);
PAINT MONO (-3590 4285);
FORCEPROP 0 LASTPIN (-3600 4325) $PN 201
J 0
(-3590 4335);
DISPLAY 0.680851 (-3590 4335);
PAINT MONO (-3590 4335);
FORCEPROP 0 LASTPIN (-3600 3225) $PN 94
J 0
(-3590 3235);
DISPLAY 0.680851 (-3590 3235);
PAINT MONO (-3590 3235);
FORCEPROP 0 LASTPIN (-3600 3275) $PN 93
J 0
(-3590 3285);
DISPLAY 0.680851 (-3590 3285);
PAINT MONO (-3590 3285);
FORCEPROP 2 LAST VALUE SCONN288_DDR506112002KQ
J 0
(-4800 4700);
DISPLAY 0.489362 (-4800 4700);
PAINT SKYBLUE (-4800 4700);
FORCEPROP 1 LAST MATERIAL IO
J 0
(-4950 4500);
DISPLAY 0.468085 (-4950 4500);
PAINT SKYBLUE (-4950 4500);
FORCEPROP 2 LAST PART_TYPE SMLF
J 0
(-4800 4750);
DISPLAY 1.021277 (-4800 4750);
FORCEPROP 2 LAST CDS_LIB pure_quanta
J 0
(-4350 3325);
DISPLAY INVISIBLE (-4350 3325);
FORCEPROP 1 LAST NEEDS_NO_SIZE TRUE
J 0
(-4350 3325);
DISPLAY 0.723404 (-4350 3325);
PAINT GREEN (-4350 3325);
DISPLAY INVISIBLE (-4350 3325);
FORCEPROP 1 LAST CDS_LMAN_SYM_OUTLINE -600,1150,600,-1150
J 0
(-4350 3325);
DISPLAY 0.468085 (-4350 3325);
PAINT GREEN (-4350 3325);
DISPLAY INVISIBLE (-4350 3325);
FORCEPROP 1 LAST PATH I235
J 0
(-4350 3325);
DISPLAY 0.723404 (-4350 3325);
PAINT GREEN (-4350 3325);
DISPLAY INVISIBLE (-4350 3325);
FORCEPROP 1 LAST PART_NUMBER DFHST8FS479
J 0
(-4950 4575);
DISPLAY 0.468085 (-4950 4575);
PAINT SKYBLUE (-4950 4575);
DISPLAY INVISIBLE (-4950 4575);
FORCEADD GND..1
(-2800 5500);
FORCEPROP 3 LASTPIN (-2800 5550) SIG_NAME GND\g
J 0
(-2790 5560);
DISPLAY 0.659574 (-2790 5560);
PAINT MONO (-2790 5560);
DISPLAY INVISIBLE (-2790 5560);
FORCEPROP 2 LAST ROOM MEM_EFGH_DECOUPLING_CAPS
J 0
(-2775 5575);
DISPLAY 0.659574 (-2775 5575);
PAINT RED (-2775 5575);
DISPLAY INVISIBLE (-2775 5575);
FORCEPROP 2 LAST CDS_LIB pure_quanta_power
J 0
(-2800 5500);
DISPLAY INVISIBLE (-2800 5500);
FORCEPROP 2 LAST BOM_COST MEM
J 0
(-2775 5625);
DISPLAY 0.659574 (-2775 5625);
DISPLAY INVISIBLE (-2775 5625);
FORCEPROP 1 LAST SIZE 1B
J 0
(-2725 5450);
DISPLAY 0.723404 (-2725 5450);
PAINT GREEN (-2725 5450);
DISPLAY INVISIBLE (-2725 5450);
FORCEPROP 1 LAST HDL_POWER GND
J 0
(-2800 5650);
DISPLAY 0.723404 (-2800 5650);
PAINT GREEN (-2800 5650);
DISPLAY INVISIBLE (-2800 5650);
FORCEPROP 1 LAST PATH I236
J 0
(-2725 5500);
DISPLAY 0.872340 (-2725 5500);
PAINT AQUA (-2725 5500);
DISPLAY INVISIBLE (-2725 5500);
FORCEADD Q_CAP..1
R 2
(-2800 5850);
FORCEPROP 1 LAST LOCATION C548
J 2
(-2850 5950);
DISPLAY 0.489362 (-2850 5950);
PAINT SKYBLUE (-2850 5950);
FORCEPROP 0 LAST $SEC 1
J 0
(-2850 6000);
DISPLAY 0.680851 (-2850 6000);
PAINT MONO (-2850 6000);
DISPLAY INVISIBLE (-2850 6000);
FORCEPROP 0 LAST CDS_SEC 1
J 0
(-2850 6000);
DISPLAY 0.680851 (-2850 6000);
DISPLAY INVISIBLE (-2850 6000);
FORCEPROP 1 LASTPIN (-2800 5950) $PN 1
J 2
(-2810 5930);
DISPLAY 0.489362 (-2810 5930);
PAINT MONO (-2810 5930);
FORCEPROP 1 LASTPIN (-2800 5750) $PN 2
J 2
(-2810 5730);
DISPLAY 0.489362 (-2810 5730);
PAINT MONO (-2810 5730);
FORCEPROP 1 LAST VOLTAGE 25V
J 2
(-2850 5850);
DISPLAY 0.489362 (-2850 5850);
PAINT SKYBLUE (-2850 5850);
FORCEPROP 1 LAST PACK_TYPE C0805
J 2
(-2850 5650);
DISPLAY 0.489362 (-2850 5650);
PAINT SKYBLUE (-2850 5650);
FORCEPROP 1 LAST MATERIAL X6S
J 2
(-2850 5750);
DISPLAY 0.489362 (-2850 5750);
PAINT SKYBLUE (-2850 5750);
FORCEPROP 1 LAST TOLERANCE 10%
J 2
(-2850 5800);
DISPLAY 0.489362 (-2850 5800);
PAINT SKYBLUE (-2850 5800);
FORCEPROP 1 LAST VALUE 10UF
J 2
(-2850 5900);
DISPLAY 0.489362 (-2850 5900);
PAINT SKYBLUE (-2850 5900);
FORCEPROP 2 LAST CDS_LIB pure_quanta
J 0
(-2800 5850);
DISPLAY INVISIBLE (-2800 5850);
FORCEPROP 0 LAST BOM_COST MEM
J 2
(-2855 5995);
DISPLAY 0.595745 (-2855 5995);
PAINT MONO (-2855 5995);
DISPLAY INVISIBLE (-2855 5995);
FORCEPROP 2 LAST ROOM 
J 2
(-2855 5995);
DISPLAY 0.595745 (-2855 5995);
PAINT RED (-2855 5995);
DISPLAY INVISIBLE (-2855 5995);
FORCEPROP 1 LAST PATH I237
J 2
(-2850 6000);
DISPLAY 0.978723 (-2850 6000);
PAINT WHITE (-2850 6000);
DISPLAY INVISIBLE (-2850 6000);
FORCEPROP 1 LAST PART_NUMBER CH6104KEA00
J 2
(-2850 5700);
DISPLAY 0.489362 (-2850 5700);
PAINT SKYBLUE (-2850 5700);
DISPLAY INVISIBLE (-2850 5700);
FORCEADD Q_CAP..1
R 2
(-2225 5850);
FORCEPROP 1 LAST LOCATION C549
J 2
(-2275 5950);
DISPLAY 0.489362 (-2275 5950);
PAINT SKYBLUE (-2275 5950);
FORCEPROP 0 LAST $SEC 1
J 0
(-2275 6000);
DISPLAY 0.680851 (-2275 6000);
PAINT MONO (-2275 6000);
DISPLAY INVISIBLE (-2275 6000);
FORCEPROP 0 LAST CDS_SEC 1
J 0
(-2275 6000);
DISPLAY 0.680851 (-2275 6000);
DISPLAY INVISIBLE (-2275 6000);
FORCEPROP 1 LASTPIN (-2225 5950) $PN 1
J 2
(-2235 5930);
DISPLAY 0.489362 (-2235 5930);
PAINT MONO (-2235 5930);
FORCEPROP 1 LASTPIN (-2225 5750) $PN 2
J 2
(-2235 5730);
DISPLAY 0.489362 (-2235 5730);
PAINT MONO (-2235 5730);
FORCEPROP 1 LAST MATERIAL X6S
J 2
(-2275 5750);
DISPLAY 0.489362 (-2275 5750);
PAINT SKYBLUE (-2275 5750);
FORCEPROP 1 LAST TOLERANCE 10%
J 2
(-2275 5800);
DISPLAY 0.489362 (-2275 5800);
PAINT SKYBLUE (-2275 5800);
FORCEPROP 1 LAST VOLTAGE 25V
J 2
(-2275 5850);
DISPLAY 0.489362 (-2275 5850);
PAINT SKYBLUE (-2275 5850);
FORCEPROP 1 LAST PACK_TYPE C0805
J 2
(-2275 5650);
DISPLAY 0.489362 (-2275 5650);
PAINT SKYBLUE (-2275 5650);
FORCEPROP 1 LAST VALUE 10UF
J 2
(-2275 5900);
DISPLAY 0.489362 (-2275 5900);
PAINT SKYBLUE (-2275 5900);
FORCEPROP 2 LAST CDS_LIB pure_quanta
J 0
(-2225 5850);
DISPLAY INVISIBLE (-2225 5850);
FORCEPROP 0 LAST BOM_COST MEM
J 2
(-2280 5995);
DISPLAY 0.595745 (-2280 5995);
PAINT MONO (-2280 5995);
DISPLAY INVISIBLE (-2280 5995);
FORCEPROP 2 LAST ROOM 
J 2
(-2280 5995);
DISPLAY 0.595745 (-2280 5995);
PAINT RED (-2280 5995);
DISPLAY INVISIBLE (-2280 5995);
FORCEPROP 1 LAST PATH I238
J 2
(-2275 6000);
DISPLAY 0.978723 (-2275 6000);
PAINT WHITE (-2275 6000);
DISPLAY INVISIBLE (-2275 6000);
FORCEPROP 1 LAST PART_NUMBER CH6104KEA00
J 2
(-2275 5700);
DISPLAY 0.489362 (-2275 5700);
PAINT SKYBLUE (-2275 5700);
DISPLAY INVISIBLE (-2275 5700);
FORCEADD UNIVERSAL_POWER..1
(-2800 6175);
FORCEPROP 3 LASTPIN (-2800 6125) SIG_NAME P12V_MEM_CPU1\g
J 0
(-2790 6135);
DISPLAY 0.659574 (-2790 6135);
PAINT MONO (-2790 6135);
DISPLAY INVISIBLE (-2790 6135);
FORCEPROP 1 LAST HDL_POWER P12V_MEM_CPU1
J 1
(-2800 6225);
DISPLAY 0.489362 (-2800 6225);
PAINT GREEN (-2800 6225);
FORCEPROP 2 LAST CDS_LIB pure_quanta_power
J 0
(-2800 6175);
DISPLAY INVISIBLE (-2800 6175);
FORCEPROP 1 LAST PATH I239
J 0
(-2750 6200);
DISPLAY 0.872340 (-2750 6200);
PAINT AQUA (-2750 6200);
DISPLAY INVISIBLE (-2750 6200);
FORCEADD TAP..1
R 2
(-7650 3250);
FORCEPROP 3 LASTPIN (-7600 3250) SIG_NAME M_L_CPU1_SB_CB<1>
J 0
(-7590 3260);
DISPLAY 0.659574 (-7590 3260);
PAINT MONO (-7590 3260);
DISPLAY INVISIBLE (-7590 3260);
FORCEPROP 1 LASTPIN (-7600 3250) BN 1
J 2
(-7588 3258);
DISPLAY 0.489362 (-7588 3258);
PAINT GREEN (-7588 3258);
FORCEPROP 2 LAST CDS_LIB mstr_standard
J 0
(-7650 3250);
DISPLAY 0.723404 (-7650 3250);
PAINT MONO (-7650 3250);
DISPLAY INVISIBLE (-7650 3250);
FORCEPROP 1 LAST BODY_TYPE PLUMBING
J 2
(-7650 3300);
DISPLAY 0.872340 (-7650 3300);
PAINT GREEN (-7650 3300);
DISPLAY INVISIBLE (-7650 3300);
FORCEPROP 1 LAST HDL_TAP TRUE
J 2
(-7975 3125);
DISPLAY 0.872340 (-7975 3125);
DISPLAY INVISIBLE (-7975 3125);
FORCEPROP 1 LAST PATH I24
J 2
(-7648 3250);
DISPLAY 0.872340 (-7648 3250);
PAINT GREEN (-7648 3250);
DISPLAY INVISIBLE (-7648 3250);
FORCEADD OFFPAGE..1
(-8275 2625);
FORCEPROP 2 LAST $XR5 108 
J 0
(-9157 2625);
DISPLAY 0.638298 (-9157 2625);
PAINT MONO (-9157 2625);
FORCEPROP 2 LAST $XR4 107 
J 0
(-9037 2625);
DISPLAY 0.638298 (-9037 2625);
PAINT MONO (-9037 2625);
FORCEPROP 2 LAST $XR3 106 
J 0
(-8917 2625);
DISPLAY 0.638298 (-8917 2625);
PAINT MONO (-8917 2625);
FORCEPROP 2 LAST $XR2 105 
J 0
(-8797 2625);
DISPLAY 0.638298 (-8797 2625);
PAINT MONO (-8797 2625);
FORCEPROP 2 LAST $XR1 104 
J 0
(-8677 2625);
DISPLAY 0.638298 (-8677 2625);
PAINT MONO (-8677 2625);
FORCEPROP 2 LAST $XR0 159 
J 0
(-8557 2625);
DISPLAY 0.638298 (-8557 2625);
PAINT MONO (-8557 2625);
FORCEPROP 2 LAST CDS_LIB mstr_standard
J 0
(-8275 2625);
DISPLAY 0.808511 (-8275 2625);
DISPLAY INVISIBLE (-8275 2625);
FORCEPROP 1 LAST OFFPAGE TRUE
J 0
(-7950 2500);
DISPLAY 0.872340 (-7950 2500);
PAINT GREEN (-7950 2500);
DISPLAY INVISIBLE (-7950 2500);
FORCEPROP 1 LAST COMMENT_BODY TRUE
J 0
(-8150 2525);
DISPLAY 0.872340 (-8150 2525);
PAINT GREEN (-8150 2525);
DISPLAY INVISIBLE (-8150 2525);
FORCEPROP 2 LAST PATH I240
J 0
(-8550 2675);
DISPLAY 0.680851 (-8550 2675);
DISPLAY INVISIBLE (-8550 2675);
FORCEADD Q_RES..1
(-7700 2625);
FORCEPROP 1 LAST LOCATION R1591
J 0
(-7750 2650);
DISPLAY 0.510638 (-7750 2650);
PAINT SKYBLUE (-7750 2650);
FORCEPROP 0 LAST $SEC 1
J 0
(-7750 2725);
DISPLAY 0.680851 (-7750 2725);
PAINT MONO (-7750 2725);
DISPLAY INVISIBLE (-7750 2725);
FORCEPROP 0 LAST CDS_SEC 1
J 0
(-7750 2725);
DISPLAY 0.680851 (-7750 2725);
DISPLAY INVISIBLE (-7750 2725);
FORCEPROP 1 LASTPIN (-7800 2625) $PN 1
J 0
(-7788 2637);
DISPLAY 0.787234 (-7788 2637);
PAINT MONO (-7788 2637);
FORCEPROP 1 LASTPIN (-7600 2625) $PN 2
J 0
(-7638 2637);
DISPLAY 0.787234 (-7638 2637);
PAINT MONO (-7638 2637);
FORCEPROP 1 LAST VALUE 49.9
J 2
(-7525 2675);
DISPLAY 0.510638 (-7525 2675);
PAINT SKYBLUE (-7525 2675);
FORCEPROP 1 LAST TOLERANCE 1%
J 0
(-7700 2525);
DISPLAY 0.978723 (-7700 2525);
DISPLAY INVISIBLE (-7700 2525);
FORCEPROP 1 LAST WATTAGE 1/16W
J 2
(-7725 2475);
DISPLAY 0.978723 (-7725 2475);
DISPLAY INVISIBLE (-7725 2475);
FORCEPROP 1 LAST PACK_TYPE 0402LF
J 0
(-7450 2475);
DISPLAY 0.978723 (-7450 2475);
DISPLAY INVISIBLE (-7450 2475);
FORCEPROP 1 LAST MATERIAL CHIP
J 0
(-7700 2475);
DISPLAY 0.978723 (-7700 2475);
DISPLAY INVISIBLE (-7700 2475);
FORCEPROP 2 LAST CDS_LIB pure_quanta
J 0
(-7700 2625);
DISPLAY INVISIBLE (-7700 2625);
FORCEPROP 1 LAST PATH I241
J 0
(-7750 2775);
DISPLAY 0.978723 (-7750 2775);
PAINT WHITE (-7750 2775);
DISPLAY INVISIBLE (-7750 2775);
FORCEPROP 1 LAST PART_NUMBER CS04992FB07
J 0
(-7750 2725);
DISPLAY 0.978723 (-7750 2725);
DISPLAY INVISIBLE (-7750 2725);
FORCEADD Q_RES..1
(-8075 2850);
FORCEPROP 1 LAST LOCATION R1711
J 0
(-8250 2850);
DISPLAY 0.510638 (-8250 2850);
FORCEPROP 0 LAST $SEC 1
J 0
(-8225 2900);
DISPLAY 0.680851 (-8225 2900);
PAINT MONO (-8225 2900);
DISPLAY INVISIBLE (-8225 2900);
FORCEPROP 0 LAST CDS_SEC 1
J 0
(-8225 2900);
DISPLAY 0.680851 (-8225 2900);
DISPLAY INVISIBLE (-8225 2900);
FORCEPROP 1 LASTPIN (-8175 2850) $PN 1
J 0
(-8163 2862);
DISPLAY 0.787234 (-8163 2862);
PAINT MONO (-8163 2862);
FORCEPROP 1 LASTPIN (-7975 2850) $PN 2
J 0
(-8013 2862);
DISPLAY 0.787234 (-8013 2862);
PAINT MONO (-8013 2862);
FORCEPROP 1 LAST MATERIAL CHIP
J 0
(-8175 2825);
DISPLAY 0.404255 (-8175 2825);
FORCEPROP 1 LAST PACK_TYPE 0402LF
J 0
(-8025 2825);
DISPLAY 0.404255 (-8025 2825);
FORCEPROP 1 LAST VALUE 10
J 2
(-7925 2850);
DISPLAY 0.404255 (-7925 2850);
FORCEPROP 1 LAST TOLERANCE 1%
J 0
(-8075 2750);
DISPLAY 0.978723 (-8075 2750);
DISPLAY INVISIBLE (-8075 2750);
FORCEPROP 1 LAST WATTAGE 1/16W
J 2
(-8100 2700);
DISPLAY 0.978723 (-8100 2700);
DISPLAY INVISIBLE (-8100 2700);
FORCEPROP 2 LAST CDS_LIB pure_quanta
J 0
(-8075 2850);
DISPLAY INVISIBLE (-8075 2850);
FORCEPROP 1 LAST PATH I242
J 0
(-8125 3000);
DISPLAY 0.978723 (-8125 3000);
PAINT WHITE (-8125 3000);
DISPLAY INVISIBLE (-8125 3000);
FORCEPROP 1 LAST PART_NUMBER CS01002FB07
J 0
(-8125 2950);
DISPLAY 0.978723 (-8125 2950);
DISPLAY INVISIBLE (-8125 2950);
FORCEADD OFFPAGE..6
(-8750 2700);
FORCEPROP 2 LAST $XR5 159 
J 0
(-9270 2664);
DISPLAY 0.638298 (-9270 2664);
PAINT MONO (-9270 2664);
FORCEPROP 2 LAST $XR4 108 
J 0
(-9150 2664);
DISPLAY 0.638298 (-9150 2664);
PAINT MONO (-9150 2664);
FORCEPROP 2 LAST $XR3 107 
J 0
(-9030 2664);
DISPLAY 0.638298 (-9030 2664);
PAINT MONO (-9030 2664);
FORCEPROP 2 LAST $XR2 106 
J 0
(-9270 2700);
DISPLAY 0.638298 (-9270 2700);
PAINT MONO (-9270 2700);
FORCEPROP 2 LAST $XR1 105 
J 0
(-9150 2700);
DISPLAY 0.638298 (-9150 2700);
PAINT MONO (-9150 2700);
FORCEPROP 2 LAST $XR0 104 
J 0
(-9030 2700);
DISPLAY 0.638298 (-9030 2700);
PAINT MONO (-9030 2700);
FORCEPROP 2 LAST CDS_LIB mstr_standard
J 0
(-8750 2700);
DISPLAY 0.808511 (-8750 2700);
DISPLAY INVISIBLE (-8750 2700);
FORCEPROP 1 LAST OFFPAGE TRUE
J 0
(-8425 2575);
DISPLAY 0.872340 (-8425 2575);
PAINT GREEN (-8425 2575);
DISPLAY INVISIBLE (-8425 2575);
FORCEPROP 1 LAST COMMENT_BODY TRUE
J 0
(-8650 2625);
DISPLAY 0.872340 (-8650 2625);
PAINT GREEN (-8650 2625);
DISPLAY INVISIBLE (-8650 2625);
FORCEPROP 2 LAST PATH I243
J 0
(-9025 2750);
DISPLAY 0.680851 (-9025 2750);
DISPLAY INVISIBLE (-9025 2750);
FORCEADD TAP..1
R 2
(-7650 3300);
FORCEPROP 3 LASTPIN (-7600 3300) SIG_NAME M_L_CPU1_SB_CB<2>
J 0
(-7590 3310);
DISPLAY 0.659574 (-7590 3310);
PAINT MONO (-7590 3310);
DISPLAY INVISIBLE (-7590 3310);
FORCEPROP 1 LASTPIN (-7600 3300) BN 2
J 2
(-7588 3308);
DISPLAY 0.489362 (-7588 3308);
PAINT GREEN (-7588 3308);
FORCEPROP 2 LAST CDS_LIB mstr_standard
J 0
(-7650 3300);
DISPLAY 0.723404 (-7650 3300);
PAINT MONO (-7650 3300);
DISPLAY INVISIBLE (-7650 3300);
FORCEPROP 1 LAST BODY_TYPE PLUMBING
J 2
(-7650 3350);
DISPLAY 0.872340 (-7650 3350);
PAINT GREEN (-7650 3350);
DISPLAY INVISIBLE (-7650 3350);
FORCEPROP 1 LAST HDL_TAP TRUE
J 2
(-7975 3175);
DISPLAY 0.872340 (-7975 3175);
DISPLAY INVISIBLE (-7975 3175);
FORCEPROP 1 LAST PATH I25
J 2
(-7648 3300);
DISPLAY 0.872340 (-7648 3300);
PAINT GREEN (-7648 3300);
DISPLAY INVISIBLE (-7648 3300);
FORCEADD TAP..1
R 2
(-7650 3400);
FORCEPROP 3 LASTPIN (-7600 3400) SIG_NAME M_L_CPU1_SB_CB<4>
J 0
(-7590 3410);
DISPLAY 0.659574 (-7590 3410);
PAINT MONO (-7590 3410);
DISPLAY INVISIBLE (-7590 3410);
FORCEPROP 1 LASTPIN (-7600 3400) BN 4
J 2
(-7588 3408);
DISPLAY 0.489362 (-7588 3408);
PAINT GREEN (-7588 3408);
FORCEPROP 2 LAST CDS_LIB mstr_standard
J 0
(-7650 3400);
DISPLAY 0.723404 (-7650 3400);
PAINT MONO (-7650 3400);
DISPLAY INVISIBLE (-7650 3400);
FORCEPROP 1 LAST BODY_TYPE PLUMBING
J 2
(-7650 3450);
DISPLAY 0.872340 (-7650 3450);
PAINT GREEN (-7650 3450);
DISPLAY INVISIBLE (-7650 3450);
FORCEPROP 1 LAST HDL_TAP TRUE
J 2
(-7975 3275);
DISPLAY 0.872340 (-7975 3275);
DISPLAY INVISIBLE (-7975 3275);
FORCEPROP 1 LAST PATH I26
J 2
(-7648 3400);
DISPLAY 0.872340 (-7648 3400);
PAINT GREEN (-7648 3400);
DISPLAY INVISIBLE (-7648 3400);
FORCEADD TAP..1
R 2
(-7650 3350);
FORCEPROP 3 LASTPIN (-7600 3350) SIG_NAME M_L_CPU1_SB_CB<3>
J 0
(-7590 3360);
DISPLAY 0.659574 (-7590 3360);
PAINT MONO (-7590 3360);
DISPLAY INVISIBLE (-7590 3360);
FORCEPROP 1 LASTPIN (-7600 3350) BN 3
J 2
(-7588 3358);
DISPLAY 0.489362 (-7588 3358);
PAINT GREEN (-7588 3358);
FORCEPROP 2 LAST CDS_LIB mstr_standard
J 0
(-7650 3350);
DISPLAY 0.723404 (-7650 3350);
PAINT MONO (-7650 3350);
DISPLAY INVISIBLE (-7650 3350);
FORCEPROP 1 LAST BODY_TYPE PLUMBING
J 2
(-7650 3400);
DISPLAY 0.872340 (-7650 3400);
PAINT GREEN (-7650 3400);
DISPLAY INVISIBLE (-7650 3400);
FORCEPROP 1 LAST HDL_TAP TRUE
J 2
(-7975 3225);
DISPLAY 0.872340 (-7975 3225);
DISPLAY INVISIBLE (-7975 3225);
FORCEPROP 1 LAST PATH I27
J 2
(-7648 3350);
DISPLAY 0.872340 (-7648 3350);
PAINT GREEN (-7648 3350);
DISPLAY INVISIBLE (-7648 3350);
FORCEADD TAP..1
R 2
(-7650 3450);
FORCEPROP 3 LASTPIN (-7600 3450) SIG_NAME M_L_CPU1_SB_CB<5>
J 0
(-7590 3460);
DISPLAY 0.659574 (-7590 3460);
PAINT MONO (-7590 3460);
DISPLAY INVISIBLE (-7590 3460);
FORCEPROP 1 LASTPIN (-7600 3450) BN 5
J 2
(-7588 3458);
DISPLAY 0.489362 (-7588 3458);
PAINT GREEN (-7588 3458);
FORCEPROP 2 LAST CDS_LIB mstr_standard
J 0
(-7650 3450);
DISPLAY 0.723404 (-7650 3450);
PAINT MONO (-7650 3450);
DISPLAY INVISIBLE (-7650 3450);
FORCEPROP 1 LAST BODY_TYPE PLUMBING
J 2
(-7650 3500);
DISPLAY 0.872340 (-7650 3500);
PAINT GREEN (-7650 3500);
DISPLAY INVISIBLE (-7650 3500);
FORCEPROP 1 LAST HDL_TAP TRUE
J 2
(-7975 3325);
DISPLAY 0.872340 (-7975 3325);
DISPLAY INVISIBLE (-7975 3325);
FORCEPROP 1 LAST PATH I28
J 2
(-7648 3450);
DISPLAY 0.872340 (-7648 3450);
PAINT GREEN (-7648 3450);
DISPLAY INVISIBLE (-7648 3450);
FORCEADD TAP..1
R 2
(-7650 3550);
FORCEPROP 3 LASTPIN (-7600 3550) SIG_NAME M_L_CPU1_SB_CB<7>
J 0
(-7590 3560);
DISPLAY 0.659574 (-7590 3560);
PAINT MONO (-7590 3560);
DISPLAY INVISIBLE (-7590 3560);
FORCEPROP 1 LASTPIN (-7600 3550) BN 7
J 2
(-7588 3558);
DISPLAY 0.489362 (-7588 3558);
PAINT GREEN (-7588 3558);
FORCEPROP 2 LAST CDS_LIB mstr_standard
J 0
(-7650 3550);
DISPLAY 0.723404 (-7650 3550);
PAINT MONO (-7650 3550);
DISPLAY INVISIBLE (-7650 3550);
FORCEPROP 1 LAST BODY_TYPE PLUMBING
J 2
(-7650 3600);
DISPLAY 0.872340 (-7650 3600);
PAINT GREEN (-7650 3600);
DISPLAY INVISIBLE (-7650 3600);
FORCEPROP 1 LAST HDL_TAP TRUE
J 2
(-7975 3425);
DISPLAY 0.872340 (-7975 3425);
DISPLAY INVISIBLE (-7975 3425);
FORCEPROP 1 LAST PATH I29
J 2
(-7648 3550);
DISPLAY 0.872340 (-7648 3550);
PAINT GREEN (-7648 3550);
DISPLAY INVISIBLE (-7648 3550);
FORCEADD OFFPAGE..5
(-8250 1950);
FORCEPROP 2 LAST $XR0 48 
J 0
(-8474 1950);
DISPLAY 0.638298 (-8474 1950);
PAINT MONO (-8474 1950);
FORCEPROP 2 LAST CDS_LIB mstr_standard
J 0
(-8250 1950);
DISPLAY 0.808511 (-8250 1950);
DISPLAY INVISIBLE (-8250 1950);
FORCEPROP 1 LAST OFFPAGE TRUE
J 0
(-7925 1825);
DISPLAY 0.872340 (-7925 1825);
PAINT GREEN (-7925 1825);
DISPLAY INVISIBLE (-7925 1825);
FORCEPROP 1 LAST COMMENT_BODY TRUE
J 0
(-8150 1875);
DISPLAY 0.872340 (-8150 1875);
PAINT GREEN (-8150 1875);
DISPLAY INVISIBLE (-8150 1875);
FORCEPROP 2 LAST PATH I3
J 0
(-8500 2000);
DISPLAY 1.021277 (-8500 2000);
DISPLAY INVISIBLE (-8500 2000);
FORCEADD TAP..1
R 2
(-7650 3650);
FORCEPROP 3 LASTPIN (-7600 3650) SIG_NAME M_L_CPU1_SA_CB<0>
J 0
(-7590 3660);
DISPLAY 0.659574 (-7590 3660);
PAINT MONO (-7590 3660);
DISPLAY INVISIBLE (-7590 3660);
FORCEPROP 1 LASTPIN (-7600 3650) BN 0
J 2
(-7588 3658);
DISPLAY 0.489362 (-7588 3658);
PAINT GREEN (-7588 3658);
FORCEPROP 2 LAST CDS_LIB mstr_standard
J 0
(-7650 3650);
DISPLAY 0.723404 (-7650 3650);
PAINT MONO (-7650 3650);
DISPLAY INVISIBLE (-7650 3650);
FORCEPROP 1 LAST BODY_TYPE PLUMBING
J 2
(-7650 3700);
DISPLAY 0.872340 (-7650 3700);
PAINT GREEN (-7650 3700);
DISPLAY INVISIBLE (-7650 3700);
FORCEPROP 1 LAST HDL_TAP TRUE
J 2
(-7975 3525);
DISPLAY 0.872340 (-7975 3525);
DISPLAY INVISIBLE (-7975 3525);
FORCEPROP 1 LAST PATH I30
J 2
(-7648 3650);
DISPLAY 0.872340 (-7648 3650);
PAINT GREEN (-7648 3650);
DISPLAY INVISIBLE (-7648 3650);
FORCEADD TAP..1
R 2
(-7650 3500);
FORCEPROP 3 LASTPIN (-7600 3500) SIG_NAME M_L_CPU1_SB_CB<6>
J 0
(-7590 3510);
DISPLAY 0.659574 (-7590 3510);
PAINT MONO (-7590 3510);
DISPLAY INVISIBLE (-7590 3510);
FORCEPROP 1 LASTPIN (-7600 3500) BN 6
J 2
(-7588 3508);
DISPLAY 0.489362 (-7588 3508);
PAINT GREEN (-7588 3508);
FORCEPROP 2 LAST CDS_LIB mstr_standard
J 0
(-7650 3500);
DISPLAY 0.723404 (-7650 3500);
PAINT MONO (-7650 3500);
DISPLAY INVISIBLE (-7650 3500);
FORCEPROP 1 LAST BODY_TYPE PLUMBING
J 2
(-7650 3550);
DISPLAY 0.872340 (-7650 3550);
PAINT GREEN (-7650 3550);
DISPLAY INVISIBLE (-7650 3550);
FORCEPROP 1 LAST HDL_TAP TRUE
J 2
(-7975 3375);
DISPLAY 0.872340 (-7975 3375);
DISPLAY INVISIBLE (-7975 3375);
FORCEPROP 1 LAST PATH I31
J 2
(-7648 3500);
DISPLAY 0.872340 (-7648 3500);
PAINT GREEN (-7648 3500);
DISPLAY INVISIBLE (-7648 3500);
FORCEADD TAP..1
(-5950 2300);
FORCEPROP 3 LASTPIN (-6000 2300) SIG_NAME M_L_CPU1_SB_DQ<2>
J 0
(-5990 2310);
DISPLAY 0.659574 (-5990 2310);
PAINT MONO (-5990 2310);
DISPLAY INVISIBLE (-5990 2310);
FORCEPROP 1 LASTPIN (-6000 2300) BN 2
J 0
(-6012 2308);
DISPLAY 0.489362 (-6012 2308);
PAINT GREEN (-6012 2308);
FORCEPROP 2 LAST CDS_LIB mstr_standard
J 0
(-5950 2300);
DISPLAY 0.723404 (-5950 2300);
PAINT MONO (-5950 2300);
DISPLAY INVISIBLE (-5950 2300);
FORCEPROP 1 LAST BODY_TYPE PLUMBING
J 0
(-5950 2350);
DISPLAY 0.872340 (-5950 2350);
PAINT GREEN (-5950 2350);
DISPLAY INVISIBLE (-5950 2350);
FORCEPROP 1 LAST HDL_TAP TRUE
J 0
(-5625 2175);
DISPLAY 0.872340 (-5625 2175);
DISPLAY INVISIBLE (-5625 2175);
FORCEPROP 1 LAST PATH I32
J 0
(-5952 2300);
DISPLAY 0.872340 (-5952 2300);
PAINT GREEN (-5952 2300);
DISPLAY INVISIBLE (-5952 2300);
FORCEADD TAP..1
(-5950 2350);
FORCEPROP 3 LASTPIN (-6000 2350) SIG_NAME M_L_CPU1_SB_DQ<3>
J 0
(-5990 2360);
DISPLAY 0.659574 (-5990 2360);
PAINT MONO (-5990 2360);
DISPLAY INVISIBLE (-5990 2360);
FORCEPROP 1 LASTPIN (-6000 2350) BN 3
J 0
(-6012 2358);
DISPLAY 0.489362 (-6012 2358);
PAINT GREEN (-6012 2358);
FORCEPROP 2 LAST CDS_LIB mstr_standard
J 0
(-5950 2350);
DISPLAY 0.723404 (-5950 2350);
PAINT MONO (-5950 2350);
DISPLAY INVISIBLE (-5950 2350);
FORCEPROP 1 LAST BODY_TYPE PLUMBING
J 0
(-5950 2400);
DISPLAY 0.872340 (-5950 2400);
PAINT GREEN (-5950 2400);
DISPLAY INVISIBLE (-5950 2400);
FORCEPROP 1 LAST HDL_TAP TRUE
J 0
(-5625 2225);
DISPLAY 0.872340 (-5625 2225);
DISPLAY INVISIBLE (-5625 2225);
FORCEPROP 1 LAST PATH I33
J 0
(-5952 2350);
DISPLAY 0.872340 (-5952 2350);
PAINT GREEN (-5952 2350);
DISPLAY INVISIBLE (-5952 2350);
FORCEADD TAP..1
(-5950 2400);
FORCEPROP 3 LASTPIN (-6000 2400) SIG_NAME M_L_CPU1_SB_DQ<4>
J 0
(-5990 2410);
DISPLAY 0.659574 (-5990 2410);
PAINT MONO (-5990 2410);
DISPLAY INVISIBLE (-5990 2410);
FORCEPROP 1 LASTPIN (-6000 2400) BN 4
J 0
(-6012 2408);
DISPLAY 0.489362 (-6012 2408);
PAINT GREEN (-6012 2408);
FORCEPROP 2 LAST CDS_LIB mstr_standard
J 0
(-5950 2400);
DISPLAY 0.723404 (-5950 2400);
PAINT MONO (-5950 2400);
DISPLAY INVISIBLE (-5950 2400);
FORCEPROP 1 LAST BODY_TYPE PLUMBING
J 0
(-5950 2450);
DISPLAY 0.872340 (-5950 2450);
PAINT GREEN (-5950 2450);
DISPLAY INVISIBLE (-5950 2450);
FORCEPROP 1 LAST HDL_TAP TRUE
J 0
(-5625 2275);
DISPLAY 0.872340 (-5625 2275);
DISPLAY INVISIBLE (-5625 2275);
FORCEPROP 1 LAST PATH I34
J 0
(-5952 2400);
DISPLAY 0.872340 (-5952 2400);
PAINT GREEN (-5952 2400);
DISPLAY INVISIBLE (-5952 2400);
FORCEADD TAP..1
(-5950 2250);
FORCEPROP 3 LASTPIN (-6000 2250) SIG_NAME M_L_CPU1_SB_DQ<1>
J 0
(-5990 2260);
DISPLAY 0.659574 (-5990 2260);
PAINT MONO (-5990 2260);
DISPLAY INVISIBLE (-5990 2260);
FORCEPROP 1 LASTPIN (-6000 2250) BN 1
J 0
(-6012 2258);
DISPLAY 0.489362 (-6012 2258);
PAINT GREEN (-6012 2258);
FORCEPROP 2 LAST CDS_LIB mstr_standard
J 0
(-5950 2250);
DISPLAY 0.723404 (-5950 2250);
PAINT MONO (-5950 2250);
DISPLAY INVISIBLE (-5950 2250);
FORCEPROP 1 LAST BODY_TYPE PLUMBING
J 0
(-5950 2300);
DISPLAY 0.872340 (-5950 2300);
PAINT GREEN (-5950 2300);
DISPLAY INVISIBLE (-5950 2300);
FORCEPROP 1 LAST HDL_TAP TRUE
J 0
(-5625 2125);
DISPLAY 0.872340 (-5625 2125);
DISPLAY INVISIBLE (-5625 2125);
FORCEPROP 1 LAST PATH I35
J 0
(-5952 2250);
DISPLAY 0.872340 (-5952 2250);
PAINT GREEN (-5952 2250);
DISPLAY INVISIBLE (-5952 2250);
FORCEADD TAP..1
(-5950 2200);
FORCEPROP 3 LASTPIN (-6000 2200) SIG_NAME M_L_CPU1_SB_DQ<0>
J 0
(-5990 2210);
DISPLAY 0.659574 (-5990 2210);
PAINT MONO (-5990 2210);
DISPLAY INVISIBLE (-5990 2210);
FORCEPROP 1 LASTPIN (-6000 2200) BN 0
J 0
(-6012 2208);
DISPLAY 0.489362 (-6012 2208);
PAINT GREEN (-6012 2208);
FORCEPROP 2 LAST CDS_LIB mstr_standard
J 0
(-5950 2200);
DISPLAY 0.723404 (-5950 2200);
PAINT MONO (-5950 2200);
DISPLAY INVISIBLE (-5950 2200);
FORCEPROP 1 LAST BODY_TYPE PLUMBING
J 0
(-5950 2250);
DISPLAY 0.872340 (-5950 2250);
PAINT GREEN (-5950 2250);
DISPLAY INVISIBLE (-5950 2250);
FORCEPROP 1 LAST HDL_TAP TRUE
J 0
(-5625 2075);
DISPLAY 0.872340 (-5625 2075);
DISPLAY INVISIBLE (-5625 2075);
FORCEPROP 1 LAST PATH I36
J 0
(-5952 2200);
DISPLAY 0.872340 (-5952 2200);
PAINT GREEN (-5952 2200);
DISPLAY INVISIBLE (-5952 2200);
FORCEADD TAP..1
(-5950 2550);
FORCEPROP 3 LASTPIN (-6000 2550) SIG_NAME M_L_CPU1_SB_DQ<7>
J 0
(-5990 2560);
DISPLAY 0.659574 (-5990 2560);
PAINT MONO (-5990 2560);
DISPLAY INVISIBLE (-5990 2560);
FORCEPROP 1 LASTPIN (-6000 2550) BN 7
J 0
(-6012 2558);
DISPLAY 0.489362 (-6012 2558);
PAINT GREEN (-6012 2558);
FORCEPROP 2 LAST CDS_LIB mstr_standard
J 0
(-5950 2550);
DISPLAY 0.723404 (-5950 2550);
PAINT MONO (-5950 2550);
DISPLAY INVISIBLE (-5950 2550);
FORCEPROP 1 LAST BODY_TYPE PLUMBING
J 0
(-5950 2600);
DISPLAY 0.872340 (-5950 2600);
PAINT GREEN (-5950 2600);
DISPLAY INVISIBLE (-5950 2600);
FORCEPROP 1 LAST HDL_TAP TRUE
J 0
(-5625 2425);
DISPLAY 0.872340 (-5625 2425);
DISPLAY INVISIBLE (-5625 2425);
FORCEPROP 1 LAST PATH I37
J 0
(-5952 2550);
DISPLAY 0.872340 (-5952 2550);
PAINT GREEN (-5952 2550);
DISPLAY INVISIBLE (-5952 2550);
FORCEADD TAP..1
(-5950 2650);
FORCEPROP 3 LASTPIN (-6000 2650) SIG_NAME M_L_CPU1_SB_DQ<9>
J 0
(-5990 2660);
DISPLAY 0.659574 (-5990 2660);
PAINT MONO (-5990 2660);
DISPLAY INVISIBLE (-5990 2660);
FORCEPROP 1 LASTPIN (-6000 2650) BN 9
J 0
(-6012 2658);
DISPLAY 0.489362 (-6012 2658);
PAINT GREEN (-6012 2658);
FORCEPROP 2 LAST CDS_LIB mstr_standard
J 0
(-5950 2650);
DISPLAY 0.723404 (-5950 2650);
PAINT MONO (-5950 2650);
DISPLAY INVISIBLE (-5950 2650);
FORCEPROP 1 LAST BODY_TYPE PLUMBING
J 0
(-5950 2700);
DISPLAY 0.872340 (-5950 2700);
PAINT GREEN (-5950 2700);
DISPLAY INVISIBLE (-5950 2700);
FORCEPROP 1 LAST HDL_TAP TRUE
J 0
(-5625 2525);
DISPLAY 0.872340 (-5625 2525);
DISPLAY INVISIBLE (-5625 2525);
FORCEPROP 1 LAST PATH I38
J 0
(-5952 2650);
DISPLAY 0.872340 (-5952 2650);
PAINT GREEN (-5952 2650);
DISPLAY INVISIBLE (-5952 2650);
FORCEADD TAP..1
(-5950 2600);
FORCEPROP 3 LASTPIN (-6000 2600) SIG_NAME M_L_CPU1_SB_DQ<8>
J 0
(-5990 2610);
DISPLAY 0.659574 (-5990 2610);
PAINT MONO (-5990 2610);
DISPLAY INVISIBLE (-5990 2610);
FORCEPROP 1 LASTPIN (-6000 2600) BN 8
J 0
(-6012 2608);
DISPLAY 0.489362 (-6012 2608);
PAINT GREEN (-6012 2608);
FORCEPROP 2 LAST CDS_LIB mstr_standard
J 0
(-5950 2600);
DISPLAY 0.723404 (-5950 2600);
PAINT MONO (-5950 2600);
DISPLAY INVISIBLE (-5950 2600);
FORCEPROP 1 LAST BODY_TYPE PLUMBING
J 0
(-5950 2650);
DISPLAY 0.872340 (-5950 2650);
PAINT GREEN (-5950 2650);
DISPLAY INVISIBLE (-5950 2650);
FORCEPROP 1 LAST HDL_TAP TRUE
J 0
(-5625 2475);
DISPLAY 0.872340 (-5625 2475);
DISPLAY INVISIBLE (-5625 2475);
FORCEPROP 1 LAST PATH I39
J 0
(-5952 2600);
DISPLAY 0.872340 (-5952 2600);
PAINT GREEN (-5952 2600);
DISPLAY INVISIBLE (-5952 2600);
FORCEADD OFFPAGE..1
(-8100 3100);
FORCEPROP 2 LAST $XR0 48 
J 0
(-8321 3100);
DISPLAY 0.638298 (-8321 3100);
PAINT MONO (-8321 3100);
FORCEPROP 2 LAST CDS_LIB mstr_standard
J 0
(-8100 3100);
DISPLAY 0.808511 (-8100 3100);
DISPLAY INVISIBLE (-8100 3100);
FORCEPROP 1 LAST OFFPAGE TRUE
J 0
(-7775 2975);
DISPLAY 0.872340 (-7775 2975);
PAINT GREEN (-7775 2975);
DISPLAY INVISIBLE (-7775 2975);
FORCEPROP 1 LAST COMMENT_BODY TRUE
J 0
(-7975 3000);
DISPLAY 0.872340 (-7975 3000);
PAINT GREEN (-7975 3000);
DISPLAY INVISIBLE (-7975 3000);
FORCEPROP 2 LAST PATH I4
J 0
(-8350 3150);
DISPLAY 1.021277 (-8350 3150);
DISPLAY INVISIBLE (-8350 3150);
FORCEADD TAP..1
(-5950 2500);
FORCEPROP 3 LASTPIN (-6000 2500) SIG_NAME M_L_CPU1_SB_DQ<6>
J 0
(-5990 2510);
DISPLAY 0.659574 (-5990 2510);
PAINT MONO (-5990 2510);
DISPLAY INVISIBLE (-5990 2510);
FORCEPROP 1 LASTPIN (-6000 2500) BN 6
J 0
(-6012 2508);
DISPLAY 0.489362 (-6012 2508);
PAINT GREEN (-6012 2508);
FORCEPROP 2 LAST CDS_LIB mstr_standard
J 0
(-5950 2500);
DISPLAY 0.723404 (-5950 2500);
PAINT MONO (-5950 2500);
DISPLAY INVISIBLE (-5950 2500);
FORCEPROP 1 LAST BODY_TYPE PLUMBING
J 0
(-5950 2550);
DISPLAY 0.872340 (-5950 2550);
PAINT GREEN (-5950 2550);
DISPLAY INVISIBLE (-5950 2550);
FORCEPROP 1 LAST HDL_TAP TRUE
J 0
(-5625 2375);
DISPLAY 0.872340 (-5625 2375);
DISPLAY INVISIBLE (-5625 2375);
FORCEPROP 1 LAST PATH I40
J 0
(-5952 2500);
DISPLAY 0.872340 (-5952 2500);
PAINT GREEN (-5952 2500);
DISPLAY INVISIBLE (-5952 2500);
FORCEADD TAP..1
(-5950 2450);
FORCEPROP 3 LASTPIN (-6000 2450) SIG_NAME M_L_CPU1_SB_DQ<5>
J 0
(-5990 2460);
DISPLAY 0.659574 (-5990 2460);
PAINT MONO (-5990 2460);
DISPLAY INVISIBLE (-5990 2460);
FORCEPROP 1 LASTPIN (-6000 2450) BN 5
J 0
(-6012 2458);
DISPLAY 0.489362 (-6012 2458);
PAINT GREEN (-6012 2458);
FORCEPROP 2 LAST CDS_LIB mstr_standard
J 0
(-5950 2450);
DISPLAY 0.723404 (-5950 2450);
PAINT MONO (-5950 2450);
DISPLAY INVISIBLE (-5950 2450);
FORCEPROP 1 LAST BODY_TYPE PLUMBING
J 0
(-5950 2500);
DISPLAY 0.872340 (-5950 2500);
PAINT GREEN (-5950 2500);
DISPLAY INVISIBLE (-5950 2500);
FORCEPROP 1 LAST HDL_TAP TRUE
J 0
(-5625 2325);
DISPLAY 0.872340 (-5625 2325);
DISPLAY INVISIBLE (-5625 2325);
FORCEPROP 1 LAST PATH I41
J 0
(-5952 2450);
DISPLAY 0.872340 (-5952 2450);
PAINT GREEN (-5952 2450);
DISPLAY INVISIBLE (-5952 2450);
FORCEADD TAP..1
(-5950 2850);
FORCEPROP 3 LASTPIN (-6000 2850) SIG_NAME M_L_CPU1_SB_DQ<13>
J 0
(-5990 2860);
DISPLAY 0.659574 (-5990 2860);
PAINT MONO (-5990 2860);
DISPLAY INVISIBLE (-5990 2860);
FORCEPROP 1 LASTPIN (-6000 2850) BN 13
J 0
(-6012 2858);
DISPLAY 0.489362 (-6012 2858);
PAINT GREEN (-6012 2858);
FORCEPROP 2 LAST CDS_LIB mstr_standard
J 0
(-5950 2850);
DISPLAY 0.723404 (-5950 2850);
PAINT MONO (-5950 2850);
DISPLAY INVISIBLE (-5950 2850);
FORCEPROP 1 LAST BODY_TYPE PLUMBING
J 0
(-5950 2900);
DISPLAY 0.872340 (-5950 2900);
PAINT GREEN (-5950 2900);
DISPLAY INVISIBLE (-5950 2900);
FORCEPROP 1 LAST HDL_TAP TRUE
J 0
(-5625 2725);
DISPLAY 0.872340 (-5625 2725);
DISPLAY INVISIBLE (-5625 2725);
FORCEPROP 1 LAST PATH I42
J 0
(-5952 2850);
DISPLAY 0.872340 (-5952 2850);
PAINT GREEN (-5952 2850);
DISPLAY INVISIBLE (-5952 2850);
FORCEADD TAP..1
(-5950 2900);
FORCEPROP 3 LASTPIN (-6000 2900) SIG_NAME M_L_CPU1_SB_DQ<14>
J 0
(-5990 2910);
DISPLAY 0.659574 (-5990 2910);
PAINT MONO (-5990 2910);
DISPLAY INVISIBLE (-5990 2910);
FORCEPROP 1 LASTPIN (-6000 2900) BN 14
J 0
(-6012 2908);
DISPLAY 0.489362 (-6012 2908);
PAINT GREEN (-6012 2908);
FORCEPROP 2 LAST CDS_LIB mstr_standard
J 0
(-5950 2900);
DISPLAY 0.723404 (-5950 2900);
PAINT MONO (-5950 2900);
DISPLAY INVISIBLE (-5950 2900);
FORCEPROP 1 LAST BODY_TYPE PLUMBING
J 0
(-5950 2950);
DISPLAY 0.872340 (-5950 2950);
PAINT GREEN (-5950 2950);
DISPLAY INVISIBLE (-5950 2950);
FORCEPROP 1 LAST HDL_TAP TRUE
J 0
(-5625 2775);
DISPLAY 0.872340 (-5625 2775);
DISPLAY INVISIBLE (-5625 2775);
FORCEPROP 1 LAST PATH I43
J 0
(-5952 2900);
DISPLAY 0.872340 (-5952 2900);
PAINT GREEN (-5952 2900);
DISPLAY INVISIBLE (-5952 2900);
FORCEADD TAP..1
(-5950 2800);
FORCEPROP 3 LASTPIN (-6000 2800) SIG_NAME M_L_CPU1_SB_DQ<12>
J 0
(-5990 2810);
DISPLAY 0.659574 (-5990 2810);
PAINT MONO (-5990 2810);
DISPLAY INVISIBLE (-5990 2810);
FORCEPROP 1 LASTPIN (-6000 2800) BN 12
J 0
(-6012 2808);
DISPLAY 0.489362 (-6012 2808);
PAINT GREEN (-6012 2808);
FORCEPROP 2 LAST CDS_LIB mstr_standard
J 0
(-5950 2800);
DISPLAY 0.723404 (-5950 2800);
PAINT MONO (-5950 2800);
DISPLAY INVISIBLE (-5950 2800);
FORCEPROP 1 LAST BODY_TYPE PLUMBING
J 0
(-5950 2850);
DISPLAY 0.872340 (-5950 2850);
PAINT GREEN (-5950 2850);
DISPLAY INVISIBLE (-5950 2850);
FORCEPROP 1 LAST HDL_TAP TRUE
J 0
(-5625 2675);
DISPLAY 0.872340 (-5625 2675);
DISPLAY INVISIBLE (-5625 2675);
FORCEPROP 1 LAST PATH I44
J 0
(-5952 2800);
DISPLAY 0.872340 (-5952 2800);
PAINT GREEN (-5952 2800);
DISPLAY INVISIBLE (-5952 2800);
FORCEADD TAP..1
(-5950 2750);
FORCEPROP 3 LASTPIN (-6000 2750) SIG_NAME M_L_CPU1_SB_DQ<11>
J 0
(-5990 2760);
DISPLAY 0.659574 (-5990 2760);
PAINT MONO (-5990 2760);
DISPLAY INVISIBLE (-5990 2760);
FORCEPROP 1 LASTPIN (-6000 2750) BN 11
J 0
(-6012 2758);
DISPLAY 0.489362 (-6012 2758);
PAINT GREEN (-6012 2758);
FORCEPROP 2 LAST CDS_LIB mstr_standard
J 0
(-5950 2750);
DISPLAY 0.723404 (-5950 2750);
PAINT MONO (-5950 2750);
DISPLAY INVISIBLE (-5950 2750);
FORCEPROP 1 LAST BODY_TYPE PLUMBING
J 0
(-5950 2800);
DISPLAY 0.872340 (-5950 2800);
PAINT GREEN (-5950 2800);
DISPLAY INVISIBLE (-5950 2800);
FORCEPROP 1 LAST HDL_TAP TRUE
J 0
(-5625 2625);
DISPLAY 0.872340 (-5625 2625);
DISPLAY INVISIBLE (-5625 2625);
FORCEPROP 1 LAST PATH I45
J 0
(-5952 2750);
DISPLAY 0.872340 (-5952 2750);
PAINT GREEN (-5952 2750);
DISPLAY INVISIBLE (-5952 2750);
FORCEADD TAP..1
(-5950 2700);
FORCEPROP 3 LASTPIN (-6000 2700) SIG_NAME M_L_CPU1_SB_DQ<10>
J 0
(-5990 2710);
DISPLAY 0.659574 (-5990 2710);
PAINT MONO (-5990 2710);
DISPLAY INVISIBLE (-5990 2710);
FORCEPROP 1 LASTPIN (-6000 2700) BN 10
J 0
(-6012 2708);
DISPLAY 0.489362 (-6012 2708);
PAINT GREEN (-6012 2708);
FORCEPROP 2 LAST CDS_LIB mstr_standard
J 0
(-5950 2700);
DISPLAY 0.723404 (-5950 2700);
PAINT MONO (-5950 2700);
DISPLAY INVISIBLE (-5950 2700);
FORCEPROP 1 LAST BODY_TYPE PLUMBING
J 0
(-5950 2750);
DISPLAY 0.872340 (-5950 2750);
PAINT GREEN (-5950 2750);
DISPLAY INVISIBLE (-5950 2750);
FORCEPROP 1 LAST HDL_TAP TRUE
J 0
(-5625 2575);
DISPLAY 0.872340 (-5625 2575);
DISPLAY INVISIBLE (-5625 2575);
FORCEPROP 1 LAST PATH I46
J 0
(-5952 2700);
DISPLAY 0.872340 (-5952 2700);
PAINT GREEN (-5952 2700);
DISPLAY INVISIBLE (-5952 2700);
FORCEADD TAP..1
(-5950 3100);
FORCEPROP 3 LASTPIN (-6000 3100) SIG_NAME M_L_CPU1_SB_DQ<18>
J 0
(-5990 3110);
DISPLAY 0.659574 (-5990 3110);
PAINT MONO (-5990 3110);
DISPLAY INVISIBLE (-5990 3110);
FORCEPROP 1 LASTPIN (-6000 3100) BN 18
J 0
(-6012 3108);
DISPLAY 0.489362 (-6012 3108);
PAINT GREEN (-6012 3108);
FORCEPROP 2 LAST CDS_LIB mstr_standard
J 0
(-5950 3100);
DISPLAY 0.723404 (-5950 3100);
PAINT MONO (-5950 3100);
DISPLAY INVISIBLE (-5950 3100);
FORCEPROP 1 LAST BODY_TYPE PLUMBING
J 0
(-5950 3150);
DISPLAY 0.872340 (-5950 3150);
PAINT GREEN (-5950 3150);
DISPLAY INVISIBLE (-5950 3150);
FORCEPROP 1 LAST HDL_TAP TRUE
J 0
(-5625 2975);
DISPLAY 0.872340 (-5625 2975);
DISPLAY INVISIBLE (-5625 2975);
FORCEPROP 1 LAST PATH I47
J 0
(-5952 3100);
DISPLAY 0.872340 (-5952 3100);
PAINT GREEN (-5952 3100);
DISPLAY INVISIBLE (-5952 3100);
FORCEADD TAP..1
(-5950 3150);
FORCEPROP 3 LASTPIN (-6000 3150) SIG_NAME M_L_CPU1_SB_DQ<19>
J 0
(-5990 3160);
DISPLAY 0.659574 (-5990 3160);
PAINT MONO (-5990 3160);
DISPLAY INVISIBLE (-5990 3160);
FORCEPROP 1 LASTPIN (-6000 3150) BN 19
J 0
(-6012 3158);
DISPLAY 0.489362 (-6012 3158);
PAINT GREEN (-6012 3158);
FORCEPROP 2 LAST CDS_LIB mstr_standard
J 0
(-5950 3150);
DISPLAY 0.723404 (-5950 3150);
PAINT MONO (-5950 3150);
DISPLAY INVISIBLE (-5950 3150);
FORCEPROP 1 LAST BODY_TYPE PLUMBING
J 0
(-5950 3200);
DISPLAY 0.872340 (-5950 3200);
PAINT GREEN (-5950 3200);
DISPLAY INVISIBLE (-5950 3200);
FORCEPROP 1 LAST HDL_TAP TRUE
J 0
(-5625 3025);
DISPLAY 0.872340 (-5625 3025);
DISPLAY INVISIBLE (-5625 3025);
FORCEPROP 1 LAST PATH I48
J 0
(-5952 3150);
DISPLAY 0.872340 (-5952 3150);
PAINT GREEN (-5952 3150);
DISPLAY INVISIBLE (-5952 3150);
FORCEADD TAP..1
(-5950 3050);
FORCEPROP 3 LASTPIN (-6000 3050) SIG_NAME M_L_CPU1_SB_DQ<17>
J 0
(-5990 3060);
DISPLAY 0.659574 (-5990 3060);
PAINT MONO (-5990 3060);
DISPLAY INVISIBLE (-5990 3060);
FORCEPROP 1 LASTPIN (-6000 3050) BN 17
J 0
(-6012 3058);
DISPLAY 0.489362 (-6012 3058);
PAINT GREEN (-6012 3058);
FORCEPROP 2 LAST CDS_LIB mstr_standard
J 0
(-5950 3050);
DISPLAY 0.723404 (-5950 3050);
PAINT MONO (-5950 3050);
DISPLAY INVISIBLE (-5950 3050);
FORCEPROP 1 LAST BODY_TYPE PLUMBING
J 0
(-5950 3100);
DISPLAY 0.872340 (-5950 3100);
PAINT GREEN (-5950 3100);
DISPLAY INVISIBLE (-5950 3100);
FORCEPROP 1 LAST HDL_TAP TRUE
J 0
(-5625 2925);
DISPLAY 0.872340 (-5625 2925);
DISPLAY INVISIBLE (-5625 2925);
FORCEPROP 1 LAST PATH I49
J 0
(-5952 3050);
DISPLAY 0.872340 (-5952 3050);
PAINT GREEN (-5952 3050);
DISPLAY INVISIBLE (-5952 3050);
FORCEADD VCC_CORE..1
(-8475 3425);
FORCEPROP 3 LASTPIN (-8475 3375) SIG_NAME P3V3_AUX\g
J 0
(-8465 3385);
DISPLAY 0.659574 (-8465 3385);
PAINT MONO (-8465 3385);
DISPLAY INVISIBLE (-8465 3385);
FORCEPROP 1 LAST HDL_POWER P3V3_AUX
J 1
(-8475 3475);
DISPLAY 0.489362 (-8475 3475);
PAINT GREEN (-8475 3475);
FORCEPROP 2 LAST ROOM PVCCINFAON_CPU1_CTRL
J 0
(-8475 3525);
DISPLAY 0.808511 (-8475 3525);
PAINT RED (-8475 3525);
DISPLAY INVISIBLE (-8475 3525);
FORCEPROP 0 LAST VOLTAGE 3.3
J 0
(-8750 3575);
DISPLAY 1.021277 (-8750 3575);
PAINT SKYBLUE (-8750 3575);
DISPLAY INVISIBLE (-8750 3575);
FORCEPROP 2 LAST CDS_LIB mstr_symbols
J 0
(-8475 3425);
PAINT MONO (-8475 3425);
DISPLAY INVISIBLE (-8475 3425);
FORCEPROP 1 LAST PATH I5
J 0
(-8425 3450);
DISPLAY 0.872340 (-8425 3450);
PAINT AQUA (-8425 3450);
DISPLAY INVISIBLE (-8425 3450);
FORCEADD TAP..1
(-5950 3000);
FORCEPROP 3 LASTPIN (-6000 3000) SIG_NAME M_L_CPU1_SB_DQ<16>
J 0
(-5990 3010);
DISPLAY 0.659574 (-5990 3010);
PAINT MONO (-5990 3010);
DISPLAY INVISIBLE (-5990 3010);
FORCEPROP 1 LASTPIN (-6000 3000) BN 16
J 0
(-6012 3008);
DISPLAY 0.489362 (-6012 3008);
PAINT GREEN (-6012 3008);
FORCEPROP 2 LAST CDS_LIB mstr_standard
J 0
(-5950 3000);
DISPLAY 0.723404 (-5950 3000);
PAINT MONO (-5950 3000);
DISPLAY INVISIBLE (-5950 3000);
FORCEPROP 1 LAST BODY_TYPE PLUMBING
J 0
(-5950 3050);
DISPLAY 0.872340 (-5950 3050);
PAINT GREEN (-5950 3050);
DISPLAY INVISIBLE (-5950 3050);
FORCEPROP 1 LAST HDL_TAP TRUE
J 0
(-5625 2875);
DISPLAY 0.872340 (-5625 2875);
DISPLAY INVISIBLE (-5625 2875);
FORCEPROP 1 LAST PATH I50
J 0
(-5952 3000);
DISPLAY 0.872340 (-5952 3000);
PAINT GREEN (-5952 3000);
DISPLAY INVISIBLE (-5952 3000);
FORCEADD TAP..1
(-5950 2950);
FORCEPROP 3 LASTPIN (-6000 2950) SIG_NAME M_L_CPU1_SB_DQ<15>
J 0
(-5990 2960);
DISPLAY 0.659574 (-5990 2960);
PAINT MONO (-5990 2960);
DISPLAY INVISIBLE (-5990 2960);
FORCEPROP 1 LASTPIN (-6000 2950) BN 15
J 0
(-6012 2958);
DISPLAY 0.489362 (-6012 2958);
PAINT GREEN (-6012 2958);
FORCEPROP 2 LAST CDS_LIB mstr_standard
J 0
(-5950 2950);
DISPLAY 0.723404 (-5950 2950);
PAINT MONO (-5950 2950);
DISPLAY INVISIBLE (-5950 2950);
FORCEPROP 1 LAST BODY_TYPE PLUMBING
J 0
(-5950 3000);
DISPLAY 0.872340 (-5950 3000);
PAINT GREEN (-5950 3000);
DISPLAY INVISIBLE (-5950 3000);
FORCEPROP 1 LAST HDL_TAP TRUE
J 0
(-5625 2825);
DISPLAY 0.872340 (-5625 2825);
DISPLAY INVISIBLE (-5625 2825);
FORCEPROP 1 LAST PATH I51
J 0
(-5952 2950);
DISPLAY 0.872340 (-5952 2950);
PAINT GREEN (-5952 2950);
DISPLAY INVISIBLE (-5952 2950);
FORCEADD TAP..1
(-5950 3350);
FORCEPROP 3 LASTPIN (-6000 3350) SIG_NAME M_L_CPU1_SB_DQ<23>
J 0
(-5990 3360);
DISPLAY 0.659574 (-5990 3360);
PAINT MONO (-5990 3360);
DISPLAY INVISIBLE (-5990 3360);
FORCEPROP 1 LASTPIN (-6000 3350) BN 23
J 0
(-6012 3358);
DISPLAY 0.489362 (-6012 3358);
PAINT GREEN (-6012 3358);
FORCEPROP 2 LAST CDS_LIB mstr_standard
J 0
(-5950 3350);
DISPLAY 0.723404 (-5950 3350);
PAINT MONO (-5950 3350);
DISPLAY INVISIBLE (-5950 3350);
FORCEPROP 1 LAST BODY_TYPE PLUMBING
J 0
(-5950 3400);
DISPLAY 0.872340 (-5950 3400);
PAINT GREEN (-5950 3400);
DISPLAY INVISIBLE (-5950 3400);
FORCEPROP 1 LAST HDL_TAP TRUE
J 0
(-5625 3225);
DISPLAY 0.872340 (-5625 3225);
DISPLAY INVISIBLE (-5625 3225);
FORCEPROP 1 LAST PATH I52
J 0
(-5952 3350);
DISPLAY 0.872340 (-5952 3350);
PAINT GREEN (-5952 3350);
DISPLAY INVISIBLE (-5952 3350);
FORCEADD TAP..1
(-5950 3400);
FORCEPROP 3 LASTPIN (-6000 3400) SIG_NAME M_L_CPU1_SB_DQ<24>
J 0
(-5990 3410);
DISPLAY 0.659574 (-5990 3410);
PAINT MONO (-5990 3410);
DISPLAY INVISIBLE (-5990 3410);
FORCEPROP 1 LASTPIN (-6000 3400) BN 24
J 0
(-6012 3408);
DISPLAY 0.489362 (-6012 3408);
PAINT GREEN (-6012 3408);
FORCEPROP 2 LAST CDS_LIB mstr_standard
J 0
(-5950 3400);
DISPLAY 0.723404 (-5950 3400);
PAINT MONO (-5950 3400);
DISPLAY INVISIBLE (-5950 3400);
FORCEPROP 1 LAST BODY_TYPE PLUMBING
J 0
(-5950 3450);
DISPLAY 0.872340 (-5950 3450);
PAINT GREEN (-5950 3450);
DISPLAY INVISIBLE (-5950 3450);
FORCEPROP 1 LAST HDL_TAP TRUE
J 0
(-5625 3275);
DISPLAY 0.872340 (-5625 3275);
DISPLAY INVISIBLE (-5625 3275);
FORCEPROP 1 LAST PATH I53
J 0
(-5952 3400);
DISPLAY 0.872340 (-5952 3400);
PAINT GREEN (-5952 3400);
DISPLAY INVISIBLE (-5952 3400);
FORCEADD TAP..1
(-5950 3300);
FORCEPROP 3 LASTPIN (-6000 3300) SIG_NAME M_L_CPU1_SB_DQ<22>
J 0
(-5990 3310);
DISPLAY 0.659574 (-5990 3310);
PAINT MONO (-5990 3310);
DISPLAY INVISIBLE (-5990 3310);
FORCEPROP 1 LASTPIN (-6000 3300) BN 22
J 0
(-6012 3308);
DISPLAY 0.489362 (-6012 3308);
PAINT GREEN (-6012 3308);
FORCEPROP 2 LAST CDS_LIB mstr_standard
J 0
(-5950 3300);
DISPLAY 0.723404 (-5950 3300);
PAINT MONO (-5950 3300);
DISPLAY INVISIBLE (-5950 3300);
FORCEPROP 1 LAST BODY_TYPE PLUMBING
J 0
(-5950 3350);
DISPLAY 0.872340 (-5950 3350);
PAINT GREEN (-5950 3350);
DISPLAY INVISIBLE (-5950 3350);
FORCEPROP 1 LAST HDL_TAP TRUE
J 0
(-5625 3175);
DISPLAY 0.872340 (-5625 3175);
DISPLAY INVISIBLE (-5625 3175);
FORCEPROP 1 LAST PATH I54
J 0
(-5952 3300);
DISPLAY 0.872340 (-5952 3300);
PAINT GREEN (-5952 3300);
DISPLAY INVISIBLE (-5952 3300);
FORCEADD TAP..1
(-5950 3250);
FORCEPROP 3 LASTPIN (-6000 3250) SIG_NAME M_L_CPU1_SB_DQ<21>
J 0
(-5990 3260);
DISPLAY 0.659574 (-5990 3260);
PAINT MONO (-5990 3260);
DISPLAY INVISIBLE (-5990 3260);
FORCEPROP 1 LASTPIN (-6000 3250) BN 21
J 0
(-6012 3258);
DISPLAY 0.489362 (-6012 3258);
PAINT GREEN (-6012 3258);
FORCEPROP 2 LAST CDS_LIB mstr_standard
J 0
(-5950 3250);
DISPLAY 0.723404 (-5950 3250);
PAINT MONO (-5950 3250);
DISPLAY INVISIBLE (-5950 3250);
FORCEPROP 1 LAST BODY_TYPE PLUMBING
J 0
(-5950 3300);
DISPLAY 0.872340 (-5950 3300);
PAINT GREEN (-5950 3300);
DISPLAY INVISIBLE (-5950 3300);
FORCEPROP 1 LAST HDL_TAP TRUE
J 0
(-5625 3125);
DISPLAY 0.872340 (-5625 3125);
DISPLAY INVISIBLE (-5625 3125);
FORCEPROP 1 LAST PATH I55
J 0
(-5952 3250);
DISPLAY 0.872340 (-5952 3250);
PAINT GREEN (-5952 3250);
DISPLAY INVISIBLE (-5952 3250);
FORCEADD TAP..1
(-5950 3200);
FORCEPROP 3 LASTPIN (-6000 3200) SIG_NAME M_L_CPU1_SB_DQ<20>
J 0
(-5990 3210);
DISPLAY 0.659574 (-5990 3210);
PAINT MONO (-5990 3210);
DISPLAY INVISIBLE (-5990 3210);
FORCEPROP 1 LASTPIN (-6000 3200) BN 20
J 0
(-6012 3208);
DISPLAY 0.489362 (-6012 3208);
PAINT GREEN (-6012 3208);
FORCEPROP 2 LAST CDS_LIB mstr_standard
J 0
(-5950 3200);
DISPLAY 0.723404 (-5950 3200);
PAINT MONO (-5950 3200);
DISPLAY INVISIBLE (-5950 3200);
FORCEPROP 1 LAST BODY_TYPE PLUMBING
J 0
(-5950 3250);
DISPLAY 0.872340 (-5950 3250);
PAINT GREEN (-5950 3250);
DISPLAY INVISIBLE (-5950 3250);
FORCEPROP 1 LAST HDL_TAP TRUE
J 0
(-5625 3075);
DISPLAY 0.872340 (-5625 3075);
DISPLAY INVISIBLE (-5625 3075);
FORCEPROP 1 LAST PATH I56
J 0
(-5952 3200);
DISPLAY 0.872340 (-5952 3200);
PAINT GREEN (-5952 3200);
DISPLAY INVISIBLE (-5952 3200);
FORCEADD TAP..1
(-5950 3600);
FORCEPROP 3 LASTPIN (-6000 3600) SIG_NAME M_L_CPU1_SB_DQ<28>
J 0
(-5990 3610);
DISPLAY 0.659574 (-5990 3610);
PAINT MONO (-5990 3610);
DISPLAY INVISIBLE (-5990 3610);
FORCEPROP 1 LASTPIN (-6000 3600) BN 28
J 0
(-6012 3608);
DISPLAY 0.489362 (-6012 3608);
PAINT GREEN (-6012 3608);
FORCEPROP 2 LAST CDS_LIB mstr_standard
J 0
(-5950 3600);
DISPLAY 0.723404 (-5950 3600);
PAINT MONO (-5950 3600);
DISPLAY INVISIBLE (-5950 3600);
FORCEPROP 1 LAST BODY_TYPE PLUMBING
J 0
(-5950 3650);
DISPLAY 0.872340 (-5950 3650);
PAINT GREEN (-5950 3650);
DISPLAY INVISIBLE (-5950 3650);
FORCEPROP 1 LAST HDL_TAP TRUE
J 0
(-5625 3475);
DISPLAY 0.872340 (-5625 3475);
DISPLAY INVISIBLE (-5625 3475);
FORCEPROP 1 LAST PATH I57
J 0
(-5952 3600);
DISPLAY 0.872340 (-5952 3600);
PAINT GREEN (-5952 3600);
DISPLAY INVISIBLE (-5952 3600);
FORCEADD TAP..1
(-5950 3650);
FORCEPROP 3 LASTPIN (-6000 3650) SIG_NAME M_L_CPU1_SB_DQ<29>
J 0
(-5990 3660);
DISPLAY 0.659574 (-5990 3660);
PAINT MONO (-5990 3660);
DISPLAY INVISIBLE (-5990 3660);
FORCEPROP 1 LASTPIN (-6000 3650) BN 29
J 0
(-6012 3658);
DISPLAY 0.489362 (-6012 3658);
PAINT GREEN (-6012 3658);
FORCEPROP 2 LAST CDS_LIB mstr_standard
J 0
(-5950 3650);
DISPLAY 0.723404 (-5950 3650);
PAINT MONO (-5950 3650);
DISPLAY INVISIBLE (-5950 3650);
FORCEPROP 1 LAST BODY_TYPE PLUMBING
J 0
(-5950 3700);
DISPLAY 0.872340 (-5950 3700);
PAINT GREEN (-5950 3700);
DISPLAY INVISIBLE (-5950 3700);
FORCEPROP 1 LAST HDL_TAP TRUE
J 0
(-5625 3525);
DISPLAY 0.872340 (-5625 3525);
DISPLAY INVISIBLE (-5625 3525);
FORCEPROP 1 LAST PATH I58
J 0
(-5952 3650);
DISPLAY 0.872340 (-5952 3650);
PAINT GREEN (-5952 3650);
DISPLAY INVISIBLE (-5952 3650);
FORCEADD TAP..1
(-5950 3550);
FORCEPROP 3 LASTPIN (-6000 3550) SIG_NAME M_L_CPU1_SB_DQ<27>
J 0
(-5990 3560);
DISPLAY 0.659574 (-5990 3560);
PAINT MONO (-5990 3560);
DISPLAY INVISIBLE (-5990 3560);
FORCEPROP 1 LASTPIN (-6000 3550) BN 27
J 0
(-6012 3558);
DISPLAY 0.489362 (-6012 3558);
PAINT GREEN (-6012 3558);
FORCEPROP 2 LAST CDS_LIB mstr_standard
J 0
(-5950 3550);
DISPLAY 0.723404 (-5950 3550);
PAINT MONO (-5950 3550);
DISPLAY INVISIBLE (-5950 3550);
FORCEPROP 1 LAST BODY_TYPE PLUMBING
J 0
(-5950 3600);
DISPLAY 0.872340 (-5950 3600);
PAINT GREEN (-5950 3600);
DISPLAY INVISIBLE (-5950 3600);
FORCEPROP 1 LAST HDL_TAP TRUE
J 0
(-5625 3425);
DISPLAY 0.872340 (-5625 3425);
DISPLAY INVISIBLE (-5625 3425);
FORCEPROP 1 LAST PATH I59
J 0
(-5952 3550);
DISPLAY 0.872340 (-5952 3550);
PAINT GREEN (-5952 3550);
DISPLAY INVISIBLE (-5952 3550);
FORCEADD OFFPAGE..5
(-8100 3050);
FORCEPROP 2 LAST $XR0 48 
J 0
(-8324 3050);
DISPLAY 0.638298 (-8324 3050);
PAINT MONO (-8324 3050);
FORCEPROP 2 LAST CDS_LIB mstr_standard
J 0
(-8100 3050);
DISPLAY INVISIBLE (-8100 3050);
FORCEPROP 1 LAST OFFPAGE TRUE
J 0
(-7775 2925);
DISPLAY 0.872340 (-7775 2925);
PAINT GREEN (-7775 2925);
DISPLAY INVISIBLE (-7775 2925);
FORCEPROP 1 LAST COMMENT_BODY TRUE
J 0
(-8000 2975);
DISPLAY 0.872340 (-8000 2975);
PAINT GREEN (-8000 2975);
DISPLAY INVISIBLE (-8000 2975);
FORCEPROP 2 LAST PATH I6
J 0
(-8300 3100);
DISPLAY 1.021277 (-8300 3100);
DISPLAY INVISIBLE (-8300 3100);
FORCEADD TAP..1
(-5950 3500);
FORCEPROP 3 LASTPIN (-6000 3500) SIG_NAME M_L_CPU1_SB_DQ<26>
J 0
(-5990 3510);
DISPLAY 0.659574 (-5990 3510);
PAINT MONO (-5990 3510);
DISPLAY INVISIBLE (-5990 3510);
FORCEPROP 1 LASTPIN (-6000 3500) BN 26
J 0
(-6012 3508);
DISPLAY 0.489362 (-6012 3508);
PAINT GREEN (-6012 3508);
FORCEPROP 2 LAST CDS_LIB mstr_standard
J 0
(-5950 3500);
DISPLAY 0.723404 (-5950 3500);
PAINT MONO (-5950 3500);
DISPLAY INVISIBLE (-5950 3500);
FORCEPROP 1 LAST BODY_TYPE PLUMBING
J 0
(-5950 3550);
DISPLAY 0.872340 (-5950 3550);
PAINT GREEN (-5950 3550);
DISPLAY INVISIBLE (-5950 3550);
FORCEPROP 1 LAST HDL_TAP TRUE
J 0
(-5625 3375);
DISPLAY 0.872340 (-5625 3375);
DISPLAY INVISIBLE (-5625 3375);
FORCEPROP 1 LAST PATH I60
J 0
(-5952 3500);
DISPLAY 0.872340 (-5952 3500);
PAINT GREEN (-5952 3500);
DISPLAY INVISIBLE (-5952 3500);
FORCEADD TAP..1
(-5950 3450);
FORCEPROP 3 LASTPIN (-6000 3450) SIG_NAME M_L_CPU1_SB_DQ<25>
J 0
(-5990 3460);
DISPLAY 0.659574 (-5990 3460);
PAINT MONO (-5990 3460);
DISPLAY INVISIBLE (-5990 3460);
FORCEPROP 1 LASTPIN (-6000 3450) BN 25
J 0
(-6012 3458);
DISPLAY 0.489362 (-6012 3458);
PAINT GREEN (-6012 3458);
FORCEPROP 2 LAST CDS_LIB mstr_standard
J 0
(-5950 3450);
DISPLAY 0.723404 (-5950 3450);
PAINT MONO (-5950 3450);
DISPLAY INVISIBLE (-5950 3450);
FORCEPROP 1 LAST BODY_TYPE PLUMBING
J 0
(-5950 3500);
DISPLAY 0.872340 (-5950 3500);
PAINT GREEN (-5950 3500);
DISPLAY INVISIBLE (-5950 3500);
FORCEPROP 1 LAST HDL_TAP TRUE
J 0
(-5625 3325);
DISPLAY 0.872340 (-5625 3325);
DISPLAY INVISIBLE (-5625 3325);
FORCEPROP 1 LAST PATH I61
J 0
(-5952 3450);
DISPLAY 0.872340 (-5952 3450);
PAINT GREEN (-5952 3450);
DISPLAY INVISIBLE (-5952 3450);
FORCEADD TAP..1
R 2
(-7650 3700);
FORCEPROP 3 LASTPIN (-7600 3700) SIG_NAME M_L_CPU1_SA_CB<1>
J 0
(-7590 3710);
DISPLAY 0.659574 (-7590 3710);
PAINT MONO (-7590 3710);
DISPLAY INVISIBLE (-7590 3710);
FORCEPROP 1 LASTPIN (-7600 3700) BN 1
J 2
(-7588 3708);
DISPLAY 0.489362 (-7588 3708);
PAINT GREEN (-7588 3708);
FORCEPROP 2 LAST CDS_LIB mstr_standard
J 0
(-7650 3700);
DISPLAY 0.723404 (-7650 3700);
PAINT MONO (-7650 3700);
DISPLAY INVISIBLE (-7650 3700);
FORCEPROP 1 LAST BODY_TYPE PLUMBING
J 2
(-7650 3750);
DISPLAY 0.872340 (-7650 3750);
PAINT GREEN (-7650 3750);
DISPLAY INVISIBLE (-7650 3750);
FORCEPROP 1 LAST HDL_TAP TRUE
J 2
(-7975 3575);
DISPLAY 0.872340 (-7975 3575);
DISPLAY INVISIBLE (-7975 3575);
FORCEPROP 1 LAST PATH I69
J 2
(-7648 3700);
DISPLAY 0.872340 (-7648 3700);
PAINT GREEN (-7648 3700);
DISPLAY INVISIBLE (-7648 3700);
FORCEADD TAP..1
R 2
(-7650 3750);
FORCEPROP 3 LASTPIN (-7600 3750) SIG_NAME M_L_CPU1_SA_CB<2>
J 0
(-7590 3760);
DISPLAY 0.659574 (-7590 3760);
PAINT MONO (-7590 3760);
DISPLAY INVISIBLE (-7590 3760);
FORCEPROP 1 LASTPIN (-7600 3750) BN 2
J 2
(-7588 3758);
DISPLAY 0.489362 (-7588 3758);
PAINT GREEN (-7588 3758);
FORCEPROP 2 LAST CDS_LIB mstr_standard
J 0
(-7650 3750);
DISPLAY 0.723404 (-7650 3750);
PAINT MONO (-7650 3750);
DISPLAY INVISIBLE (-7650 3750);
FORCEPROP 1 LAST BODY_TYPE PLUMBING
J 2
(-7650 3800);
DISPLAY 0.872340 (-7650 3800);
PAINT GREEN (-7650 3800);
DISPLAY INVISIBLE (-7650 3800);
FORCEPROP 1 LAST HDL_TAP TRUE
J 2
(-7975 3625);
DISPLAY 0.872340 (-7975 3625);
DISPLAY INVISIBLE (-7975 3625);
FORCEPROP 1 LAST PATH I70
J 2
(-7648 3750);
DISPLAY 0.872340 (-7648 3750);
PAINT GREEN (-7648 3750);
DISPLAY INVISIBLE (-7648 3750);
FORCEADD TAP..1
R 2
(-7650 3800);
FORCEPROP 3 LASTPIN (-7600 3800) SIG_NAME M_L_CPU1_SA_CB<3>
J 0
(-7590 3810);
DISPLAY 0.659574 (-7590 3810);
PAINT MONO (-7590 3810);
DISPLAY INVISIBLE (-7590 3810);
FORCEPROP 1 LASTPIN (-7600 3800) BN 3
J 2
(-7588 3808);
DISPLAY 0.489362 (-7588 3808);
PAINT GREEN (-7588 3808);
FORCEPROP 2 LAST CDS_LIB mstr_standard
J 0
(-7650 3800);
DISPLAY 0.723404 (-7650 3800);
PAINT MONO (-7650 3800);
DISPLAY INVISIBLE (-7650 3800);
FORCEPROP 1 LAST BODY_TYPE PLUMBING
J 2
(-7650 3850);
DISPLAY 0.872340 (-7650 3850);
PAINT GREEN (-7650 3850);
DISPLAY INVISIBLE (-7650 3850);
FORCEPROP 1 LAST HDL_TAP TRUE
J 2
(-7975 3675);
DISPLAY 0.872340 (-7975 3675);
DISPLAY INVISIBLE (-7975 3675);
FORCEPROP 1 LAST PATH I71
J 2
(-7648 3800);
DISPLAY 0.872340 (-7648 3800);
PAINT GREEN (-7648 3800);
DISPLAY INVISIBLE (-7648 3800);
FORCEADD TAP..1
R 2
(-7650 3900);
FORCEPROP 3 LASTPIN (-7600 3900) SIG_NAME M_L_CPU1_SA_CB<5>
J 0
(-7590 3910);
DISPLAY 0.659574 (-7590 3910);
PAINT MONO (-7590 3910);
DISPLAY INVISIBLE (-7590 3910);
FORCEPROP 1 LASTPIN (-7600 3900) BN 5
J 2
(-7588 3908);
DISPLAY 0.489362 (-7588 3908);
PAINT GREEN (-7588 3908);
FORCEPROP 2 LAST CDS_LIB mstr_standard
J 0
(-7650 3900);
DISPLAY 0.723404 (-7650 3900);
PAINT MONO (-7650 3900);
DISPLAY INVISIBLE (-7650 3900);
FORCEPROP 1 LAST BODY_TYPE PLUMBING
J 2
(-7650 3950);
DISPLAY 0.872340 (-7650 3950);
PAINT GREEN (-7650 3950);
DISPLAY INVISIBLE (-7650 3950);
FORCEPROP 1 LAST HDL_TAP TRUE
J 2
(-7975 3775);
DISPLAY 0.872340 (-7975 3775);
DISPLAY INVISIBLE (-7975 3775);
FORCEPROP 1 LAST PATH I72
J 2
(-7648 3900);
DISPLAY 0.872340 (-7648 3900);
PAINT GREEN (-7648 3900);
DISPLAY INVISIBLE (-7648 3900);
FORCEADD TAP..1
R 2
(-7650 3850);
FORCEPROP 3 LASTPIN (-7600 3850) SIG_NAME M_L_CPU1_SA_CB<4>
J 0
(-7590 3860);
DISPLAY 0.659574 (-7590 3860);
PAINT MONO (-7590 3860);
DISPLAY INVISIBLE (-7590 3860);
FORCEPROP 1 LASTPIN (-7600 3850) BN 4
J 2
(-7588 3858);
DISPLAY 0.489362 (-7588 3858);
PAINT GREEN (-7588 3858);
FORCEPROP 2 LAST CDS_LIB mstr_standard
J 0
(-7650 3850);
DISPLAY 0.723404 (-7650 3850);
PAINT MONO (-7650 3850);
DISPLAY INVISIBLE (-7650 3850);
FORCEPROP 1 LAST BODY_TYPE PLUMBING
J 2
(-7650 3900);
DISPLAY 0.872340 (-7650 3900);
PAINT GREEN (-7650 3900);
DISPLAY INVISIBLE (-7650 3900);
FORCEPROP 1 LAST HDL_TAP TRUE
J 2
(-7975 3725);
DISPLAY 0.872340 (-7975 3725);
DISPLAY INVISIBLE (-7975 3725);
FORCEPROP 1 LAST PATH I73
J 2
(-7648 3850);
DISPLAY 0.872340 (-7648 3850);
PAINT GREEN (-7648 3850);
DISPLAY INVISIBLE (-7648 3850);
FORCEADD TAP..1
R 2
(-7650 3950);
FORCEPROP 3 LASTPIN (-7600 3950) SIG_NAME M_L_CPU1_SA_CB<6>
J 0
(-7590 3960);
DISPLAY 0.659574 (-7590 3960);
PAINT MONO (-7590 3960);
DISPLAY INVISIBLE (-7590 3960);
FORCEPROP 1 LASTPIN (-7600 3950) BN 6
J 2
(-7588 3958);
DISPLAY 0.489362 (-7588 3958);
PAINT GREEN (-7588 3958);
FORCEPROP 2 LAST CDS_LIB mstr_standard
J 0
(-7650 3950);
DISPLAY 0.723404 (-7650 3950);
PAINT MONO (-7650 3950);
DISPLAY INVISIBLE (-7650 3950);
FORCEPROP 1 LAST BODY_TYPE PLUMBING
J 2
(-7650 4000);
DISPLAY 0.872340 (-7650 4000);
PAINT GREEN (-7650 4000);
DISPLAY INVISIBLE (-7650 4000);
FORCEPROP 1 LAST HDL_TAP TRUE
J 2
(-7975 3825);
DISPLAY 0.872340 (-7975 3825);
DISPLAY INVISIBLE (-7975 3825);
FORCEPROP 1 LAST PATH I74
J 2
(-7648 3950);
DISPLAY 0.872340 (-7648 3950);
PAINT GREEN (-7648 3950);
DISPLAY INVISIBLE (-7648 3950);
FORCEADD TAP..1
R 2
(-7650 4000);
FORCEPROP 3 LASTPIN (-7600 4000) SIG_NAME M_L_CPU1_SA_CB<7>
J 0
(-7590 4010);
DISPLAY 0.659574 (-7590 4010);
PAINT MONO (-7590 4010);
DISPLAY INVISIBLE (-7590 4010);
FORCEPROP 1 LASTPIN (-7600 4000) BN 7
J 2
(-7588 4008);
DISPLAY 0.489362 (-7588 4008);
PAINT GREEN (-7588 4008);
FORCEPROP 2 LAST CDS_LIB mstr_standard
J 0
(-7650 4000);
DISPLAY 0.723404 (-7650 4000);
PAINT MONO (-7650 4000);
DISPLAY INVISIBLE (-7650 4000);
FORCEPROP 1 LAST BODY_TYPE PLUMBING
J 2
(-7650 4050);
DISPLAY 0.872340 (-7650 4050);
PAINT GREEN (-7650 4050);
DISPLAY INVISIBLE (-7650 4050);
FORCEPROP 1 LAST HDL_TAP TRUE
J 2
(-7975 3875);
DISPLAY 0.872340 (-7975 3875);
DISPLAY INVISIBLE (-7975 3875);
FORCEPROP 1 LAST PATH I75
J 2
(-7648 4000);
DISPLAY 0.872340 (-7648 4000);
PAINT GREEN (-7648 4000);
DISPLAY INVISIBLE (-7648 4000);
FORCEADD TAP..1
R 2
(-7650 4700);
FORCEPROP 3 LASTPIN (-7600 4700) SIG_NAME M_L_CPU1_SB_CA<0>
J 0
(-7590 4710);
DISPLAY 0.659574 (-7590 4710);
PAINT MONO (-7590 4710);
DISPLAY INVISIBLE (-7590 4710);
FORCEPROP 1 LASTPIN (-7600 4700) BN 0
J 2
(-7588 4708);
DISPLAY 0.489362 (-7588 4708);
PAINT GREEN (-7588 4708);
FORCEPROP 2 LAST CDS_LIB mstr_standard
J 0
(-7650 4700);
DISPLAY 0.723404 (-7650 4700);
PAINT MONO (-7650 4700);
DISPLAY INVISIBLE (-7650 4700);
FORCEPROP 1 LAST BODY_TYPE PLUMBING
J 2
(-7650 4750);
DISPLAY 0.872340 (-7650 4750);
PAINT GREEN (-7650 4750);
DISPLAY INVISIBLE (-7650 4750);
FORCEPROP 1 LAST HDL_TAP TRUE
J 2
(-7975 4575);
DISPLAY 0.872340 (-7975 4575);
DISPLAY INVISIBLE (-7975 4575);
FORCEPROP 1 LAST PATH I76
J 2
(-7648 4700);
DISPLAY 0.872340 (-7648 4700);
PAINT GREEN (-7648 4700);
DISPLAY INVISIBLE (-7648 4700);
FORCEADD TAP..1
R 2
(-7650 4800);
FORCEPROP 3 LASTPIN (-7600 4800) SIG_NAME M_L_CPU1_SB_CA<2>
J 0
(-7590 4810);
DISPLAY 0.659574 (-7590 4810);
PAINT MONO (-7590 4810);
DISPLAY INVISIBLE (-7590 4810);
FORCEPROP 1 LASTPIN (-7600 4800) BN 2
J 2
(-7588 4808);
DISPLAY 0.489362 (-7588 4808);
PAINT GREEN (-7588 4808);
FORCEPROP 2 LAST CDS_LIB mstr_standard
J 0
(-7650 4800);
DISPLAY 0.723404 (-7650 4800);
PAINT MONO (-7650 4800);
DISPLAY INVISIBLE (-7650 4800);
FORCEPROP 1 LAST BODY_TYPE PLUMBING
J 2
(-7650 4850);
DISPLAY 0.872340 (-7650 4850);
PAINT GREEN (-7650 4850);
DISPLAY INVISIBLE (-7650 4850);
FORCEPROP 1 LAST HDL_TAP TRUE
J 2
(-7975 4675);
DISPLAY 0.872340 (-7975 4675);
DISPLAY INVISIBLE (-7975 4675);
FORCEPROP 1 LAST PATH I77
J 2
(-7648 4800);
DISPLAY 0.872340 (-7648 4800);
PAINT GREEN (-7648 4800);
DISPLAY INVISIBLE (-7648 4800);
FORCEADD TAP..1
R 2
(-7650 4750);
FORCEPROP 3 LASTPIN (-7600 4750) SIG_NAME M_L_CPU1_SB_CA<1>
J 0
(-7590 4760);
DISPLAY 0.659574 (-7590 4760);
PAINT MONO (-7590 4760);
DISPLAY INVISIBLE (-7590 4760);
FORCEPROP 1 LASTPIN (-7600 4750) BN 1
J 2
(-7588 4758);
DISPLAY 0.489362 (-7588 4758);
PAINT GREEN (-7588 4758);
FORCEPROP 2 LAST CDS_LIB mstr_standard
J 0
(-7650 4750);
DISPLAY 0.723404 (-7650 4750);
PAINT MONO (-7650 4750);
DISPLAY INVISIBLE (-7650 4750);
FORCEPROP 1 LAST BODY_TYPE PLUMBING
J 2
(-7650 4800);
DISPLAY 0.872340 (-7650 4800);
PAINT GREEN (-7650 4800);
DISPLAY INVISIBLE (-7650 4800);
FORCEPROP 1 LAST HDL_TAP TRUE
J 2
(-7975 4625);
DISPLAY 0.872340 (-7975 4625);
DISPLAY INVISIBLE (-7975 4625);
FORCEPROP 1 LAST PATH I78
J 2
(-7648 4750);
DISPLAY 0.872340 (-7648 4750);
PAINT GREEN (-7648 4750);
DISPLAY INVISIBLE (-7648 4750);
FORCEADD TAP..1
R 2
(-7650 4850);
FORCEPROP 3 LASTPIN (-7600 4850) SIG_NAME M_L_CPU1_SB_CA<3>
J 0
(-7590 4860);
DISPLAY 0.659574 (-7590 4860);
PAINT MONO (-7590 4860);
DISPLAY INVISIBLE (-7590 4860);
FORCEPROP 1 LASTPIN (-7600 4850) BN 3
J 2
(-7588 4858);
DISPLAY 0.489362 (-7588 4858);
PAINT GREEN (-7588 4858);
FORCEPROP 2 LAST CDS_LIB mstr_standard
J 0
(-7650 4850);
DISPLAY 0.723404 (-7650 4850);
PAINT MONO (-7650 4850);
DISPLAY INVISIBLE (-7650 4850);
FORCEPROP 1 LAST BODY_TYPE PLUMBING
J 2
(-7650 4900);
DISPLAY 0.872340 (-7650 4900);
PAINT GREEN (-7650 4900);
DISPLAY INVISIBLE (-7650 4900);
FORCEPROP 1 LAST HDL_TAP TRUE
J 2
(-7975 4725);
DISPLAY 0.872340 (-7975 4725);
DISPLAY INVISIBLE (-7975 4725);
FORCEPROP 1 LAST PATH I79
J 2
(-7648 4850);
DISPLAY 0.872340 (-7648 4850);
PAINT GREEN (-7648 4850);
DISPLAY INVISIBLE (-7648 4850);
FORCEADD OFFPAGE..6
(-8250 3600);
FORCEPROP 2 LAST $XR0 48 
J 0
(-8529 3600);
DISPLAY 0.638298 (-8529 3600);
PAINT MONO (-8529 3600);
FORCEPROP 2 LAST CDS_LIB mstr_standard
J 0
(-8250 3600);
DISPLAY 0.723404 (-8250 3600);
PAINT MONO (-8250 3600);
DISPLAY INVISIBLE (-8250 3600);
FORCEPROP 1 LAST OFFPAGE TRUE
J 0
(-7925 3475);
DISPLAY 0.872340 (-7925 3475);
PAINT GREEN (-7925 3475);
DISPLAY INVISIBLE (-7925 3475);
FORCEPROP 1 LAST COMMENT_BODY TRUE
J 0
(-8150 3525);
DISPLAY 0.872340 (-8150 3525);
PAINT GREEN (-8150 3525);
DISPLAY INVISIBLE (-8150 3525);
FORCEPROP 2 LAST PATH I8
J 0
(-8475 3650);
DISPLAY 1.021277 (-8475 3650);
DISPLAY INVISIBLE (-8475 3650);
FORCEADD TAP..1
R 2
(-7650 4900);
FORCEPROP 3 LASTPIN (-7600 4900) SIG_NAME M_L_CPU1_SB_CA<4>
J 0
(-7590 4910);
DISPLAY 0.659574 (-7590 4910);
PAINT MONO (-7590 4910);
DISPLAY INVISIBLE (-7590 4910);
FORCEPROP 1 LASTPIN (-7600 4900) BN 4
J 2
(-7588 4908);
DISPLAY 0.489362 (-7588 4908);
PAINT GREEN (-7588 4908);
FORCEPROP 2 LAST CDS_LIB mstr_standard
J 0
(-7650 4900);
DISPLAY 0.723404 (-7650 4900);
PAINT MONO (-7650 4900);
DISPLAY INVISIBLE (-7650 4900);
FORCEPROP 1 LAST BODY_TYPE PLUMBING
J 2
(-7650 4950);
DISPLAY 0.872340 (-7650 4950);
PAINT GREEN (-7650 4950);
DISPLAY INVISIBLE (-7650 4950);
FORCEPROP 1 LAST HDL_TAP TRUE
J 2
(-7975 4775);
DISPLAY 0.872340 (-7975 4775);
DISPLAY INVISIBLE (-7975 4775);
FORCEPROP 1 LAST PATH I80
J 2
(-7648 4900);
DISPLAY 0.872340 (-7648 4900);
PAINT GREEN (-7648 4900);
DISPLAY INVISIBLE (-7648 4900);
FORCEADD TAP..1
R 2
(-7650 4950);
FORCEPROP 3 LASTPIN (-7600 4950) SIG_NAME M_L_CPU1_SB_CA<5>
J 0
(-7590 4960);
DISPLAY 0.659574 (-7590 4960);
PAINT MONO (-7590 4960);
DISPLAY INVISIBLE (-7590 4960);
FORCEPROP 1 LASTPIN (-7600 4950) BN 5
J 2
(-7588 4958);
DISPLAY 0.489362 (-7588 4958);
PAINT GREEN (-7588 4958);
FORCEPROP 2 LAST CDS_LIB mstr_standard
J 0
(-7650 4950);
DISPLAY 0.723404 (-7650 4950);
PAINT MONO (-7650 4950);
DISPLAY INVISIBLE (-7650 4950);
FORCEPROP 1 LAST BODY_TYPE PLUMBING
J 2
(-7650 5000);
DISPLAY 0.872340 (-7650 5000);
PAINT GREEN (-7650 5000);
DISPLAY INVISIBLE (-7650 5000);
FORCEPROP 1 LAST HDL_TAP TRUE
J 2
(-7975 4825);
DISPLAY 0.872340 (-7975 4825);
DISPLAY INVISIBLE (-7975 4825);
FORCEPROP 1 LAST PATH I81
J 2
(-7648 4950);
DISPLAY 0.872340 (-7648 4950);
PAINT GREEN (-7648 4950);
DISPLAY INVISIBLE (-7648 4950);
FORCEADD TAP..1
R 2
(-7650 5150);
FORCEPROP 3 LASTPIN (-7600 5150) SIG_NAME M_L_CPU1_SA_CA<1>
J 0
(-7590 5160);
DISPLAY 0.659574 (-7590 5160);
PAINT MONO (-7590 5160);
DISPLAY INVISIBLE (-7590 5160);
FORCEPROP 1 LASTPIN (-7600 5150) BN 1
J 2
(-7588 5158);
DISPLAY 0.489362 (-7588 5158);
PAINT GREEN (-7588 5158);
FORCEPROP 2 LAST CDS_LIB mstr_standard
J 0
(-7650 5150);
DISPLAY 0.723404 (-7650 5150);
PAINT MONO (-7650 5150);
DISPLAY INVISIBLE (-7650 5150);
FORCEPROP 1 LAST BODY_TYPE PLUMBING
J 2
(-7650 5200);
DISPLAY 0.872340 (-7650 5200);
PAINT GREEN (-7650 5200);
DISPLAY INVISIBLE (-7650 5200);
FORCEPROP 1 LAST HDL_TAP TRUE
J 2
(-7975 5025);
DISPLAY 0.872340 (-7975 5025);
DISPLAY INVISIBLE (-7975 5025);
FORCEPROP 1 LAST PATH I82
J 2
(-7648 5150);
DISPLAY 0.872340 (-7648 5150);
PAINT GREEN (-7648 5150);
DISPLAY INVISIBLE (-7648 5150);
FORCEADD TAP..1
R 2
(-7650 5200);
FORCEPROP 3 LASTPIN (-7600 5200) SIG_NAME M_L_CPU1_SA_CA<2>
J 0
(-7590 5210);
DISPLAY 0.659574 (-7590 5210);
PAINT MONO (-7590 5210);
DISPLAY INVISIBLE (-7590 5210);
FORCEPROP 1 LASTPIN (-7600 5200) BN 2
J 2
(-7588 5208);
DISPLAY 0.489362 (-7588 5208);
PAINT GREEN (-7588 5208);
FORCEPROP 2 LAST CDS_LIB mstr_standard
J 0
(-7650 5200);
DISPLAY 0.723404 (-7650 5200);
PAINT MONO (-7650 5200);
DISPLAY INVISIBLE (-7650 5200);
FORCEPROP 1 LAST BODY_TYPE PLUMBING
J 2
(-7650 5250);
DISPLAY 0.872340 (-7650 5250);
PAINT GREEN (-7650 5250);
DISPLAY INVISIBLE (-7650 5250);
FORCEPROP 1 LAST HDL_TAP TRUE
J 2
(-7975 5075);
DISPLAY 0.872340 (-7975 5075);
DISPLAY INVISIBLE (-7975 5075);
FORCEPROP 1 LAST PATH I83
J 2
(-7648 5200);
DISPLAY 0.872340 (-7648 5200);
PAINT GREEN (-7648 5200);
DISPLAY INVISIBLE (-7648 5200);
FORCEADD TAP..1
R 2
(-7650 5100);
FORCEPROP 3 LASTPIN (-7600 5100) SIG_NAME M_L_CPU1_SA_CA<0>
J 0
(-7590 5110);
DISPLAY 0.659574 (-7590 5110);
PAINT MONO (-7590 5110);
DISPLAY INVISIBLE (-7590 5110);
FORCEPROP 1 LASTPIN (-7600 5100) BN 0
J 2
(-7588 5108);
DISPLAY 0.489362 (-7588 5108);
PAINT GREEN (-7588 5108);
FORCEPROP 2 LAST CDS_LIB mstr_standard
J 0
(-7650 5100);
DISPLAY 0.723404 (-7650 5100);
PAINT MONO (-7650 5100);
DISPLAY INVISIBLE (-7650 5100);
FORCEPROP 1 LAST BODY_TYPE PLUMBING
J 2
(-7650 5150);
DISPLAY 0.872340 (-7650 5150);
PAINT GREEN (-7650 5150);
DISPLAY INVISIBLE (-7650 5150);
FORCEPROP 1 LAST HDL_TAP TRUE
J 2
(-7975 4975);
DISPLAY 0.872340 (-7975 4975);
DISPLAY INVISIBLE (-7975 4975);
FORCEPROP 1 LAST PATH I84
J 2
(-7648 5100);
DISPLAY 0.872340 (-7648 5100);
PAINT GREEN (-7648 5100);
DISPLAY INVISIBLE (-7648 5100);
FORCEADD TAP..1
R 2
(-7650 5000);
FORCEPROP 3 LASTPIN (-7600 5000) SIG_NAME M_L_CPU1_SB_CA<6>
J 0
(-7590 5010);
DISPLAY 0.659574 (-7590 5010);
PAINT MONO (-7590 5010);
DISPLAY INVISIBLE (-7590 5010);
FORCEPROP 1 LASTPIN (-7600 5000) BN 6
J 2
(-7588 5008);
DISPLAY 0.489362 (-7588 5008);
PAINT GREEN (-7588 5008);
FORCEPROP 2 LAST CDS_LIB mstr_standard
J 0
(-7650 5000);
DISPLAY 0.723404 (-7650 5000);
PAINT MONO (-7650 5000);
DISPLAY INVISIBLE (-7650 5000);
FORCEPROP 1 LAST BODY_TYPE PLUMBING
J 2
(-7650 5050);
DISPLAY 0.872340 (-7650 5050);
PAINT GREEN (-7650 5050);
DISPLAY INVISIBLE (-7650 5050);
FORCEPROP 1 LAST HDL_TAP TRUE
J 2
(-7975 4875);
DISPLAY 0.872340 (-7975 4875);
DISPLAY INVISIBLE (-7975 4875);
FORCEPROP 1 LAST PATH I85
J 2
(-7648 5000);
DISPLAY 0.872340 (-7648 5000);
PAINT GREEN (-7648 5000);
DISPLAY INVISIBLE (-7648 5000);
FORCEADD TAP..1
R 2
(-7650 5250);
FORCEPROP 3 LASTPIN (-7600 5250) SIG_NAME M_L_CPU1_SA_CA<3>
J 0
(-7590 5260);
DISPLAY 0.659574 (-7590 5260);
PAINT MONO (-7590 5260);
DISPLAY INVISIBLE (-7590 5260);
FORCEPROP 1 LASTPIN (-7600 5250) BN 3
J 2
(-7588 5258);
DISPLAY 0.489362 (-7588 5258);
PAINT GREEN (-7588 5258);
FORCEPROP 2 LAST CDS_LIB mstr_standard
J 0
(-7650 5250);
DISPLAY 0.723404 (-7650 5250);
PAINT MONO (-7650 5250);
DISPLAY INVISIBLE (-7650 5250);
FORCEPROP 1 LAST BODY_TYPE PLUMBING
J 2
(-7650 5300);
DISPLAY 0.872340 (-7650 5300);
PAINT GREEN (-7650 5300);
DISPLAY INVISIBLE (-7650 5300);
FORCEPROP 1 LAST HDL_TAP TRUE
J 2
(-7975 5125);
DISPLAY 0.872340 (-7975 5125);
DISPLAY INVISIBLE (-7975 5125);
FORCEPROP 1 LAST PATH I86
J 2
(-7648 5250);
DISPLAY 0.872340 (-7648 5250);
PAINT GREEN (-7648 5250);
DISPLAY INVISIBLE (-7648 5250);
FORCEADD TAP..1
R 2
(-7650 5300);
FORCEPROP 3 LASTPIN (-7600 5300) SIG_NAME M_L_CPU1_SA_CA<4>
J 0
(-7590 5310);
DISPLAY 0.659574 (-7590 5310);
PAINT MONO (-7590 5310);
DISPLAY INVISIBLE (-7590 5310);
FORCEPROP 1 LASTPIN (-7600 5300) BN 4
J 2
(-7588 5308);
DISPLAY 0.489362 (-7588 5308);
PAINT GREEN (-7588 5308);
FORCEPROP 2 LAST CDS_LIB mstr_standard
J 0
(-7650 5300);
DISPLAY 0.723404 (-7650 5300);
PAINT MONO (-7650 5300);
DISPLAY INVISIBLE (-7650 5300);
FORCEPROP 1 LAST BODY_TYPE PLUMBING
J 2
(-7650 5350);
DISPLAY 0.872340 (-7650 5350);
PAINT GREEN (-7650 5350);
DISPLAY INVISIBLE (-7650 5350);
FORCEPROP 1 LAST HDL_TAP TRUE
J 2
(-7975 5175);
DISPLAY 0.872340 (-7975 5175);
DISPLAY INVISIBLE (-7975 5175);
FORCEPROP 1 LAST PATH I87
J 2
(-7648 5300);
DISPLAY 0.872340 (-7648 5300);
PAINT GREEN (-7648 5300);
DISPLAY INVISIBLE (-7648 5300);
FORCEADD TAP..1
R 2
(-7650 5350);
FORCEPROP 3 LASTPIN (-7600 5350) SIG_NAME M_L_CPU1_SA_CA<5>
J 0
(-7590 5360);
DISPLAY 0.659574 (-7590 5360);
PAINT MONO (-7590 5360);
DISPLAY INVISIBLE (-7590 5360);
FORCEPROP 1 LASTPIN (-7600 5350) BN 5
J 2
(-7588 5358);
DISPLAY 0.489362 (-7588 5358);
PAINT GREEN (-7588 5358);
FORCEPROP 2 LAST CDS_LIB mstr_standard
J 0
(-7650 5350);
DISPLAY 0.723404 (-7650 5350);
PAINT MONO (-7650 5350);
DISPLAY INVISIBLE (-7650 5350);
FORCEPROP 1 LAST BODY_TYPE PLUMBING
J 2
(-7650 5400);
DISPLAY 0.872340 (-7650 5400);
PAINT GREEN (-7650 5400);
DISPLAY INVISIBLE (-7650 5400);
FORCEPROP 1 LAST HDL_TAP TRUE
J 2
(-7975 5225);
DISPLAY 0.872340 (-7975 5225);
DISPLAY INVISIBLE (-7975 5225);
FORCEPROP 1 LAST PATH I88
J 2
(-7648 5350);
DISPLAY 0.872340 (-7648 5350);
PAINT GREEN (-7648 5350);
DISPLAY INVISIBLE (-7648 5350);
FORCEADD TAP..1
R 2
(-7650 5400);
FORCEPROP 3 LASTPIN (-7600 5400) SIG_NAME M_L_CPU1_SA_CA<6>
J 0
(-7590 5410);
DISPLAY 0.659574 (-7590 5410);
PAINT MONO (-7590 5410);
DISPLAY INVISIBLE (-7590 5410);
FORCEPROP 1 LASTPIN (-7600 5400) BN 6
J 2
(-7588 5408);
DISPLAY 0.489362 (-7588 5408);
PAINT GREEN (-7588 5408);
FORCEPROP 2 LAST CDS_LIB mstr_standard
J 0
(-7650 5400);
DISPLAY 0.723404 (-7650 5400);
PAINT MONO (-7650 5400);
DISPLAY INVISIBLE (-7650 5400);
FORCEPROP 1 LAST BODY_TYPE PLUMBING
J 2
(-7650 5450);
DISPLAY 0.872340 (-7650 5450);
PAINT GREEN (-7650 5450);
DISPLAY INVISIBLE (-7650 5450);
FORCEPROP 1 LAST HDL_TAP TRUE
J 2
(-7975 5275);
DISPLAY 0.872340 (-7975 5275);
DISPLAY INVISIBLE (-7975 5275);
FORCEPROP 1 LAST PATH I89
J 2
(-7648 5400);
DISPLAY 0.872340 (-7648 5400);
PAINT GREEN (-7648 5400);
DISPLAY INVISIBLE (-7648 5400);
FORCEADD OFFPAGE..1
(-8625 2900);
FORCEPROP 2 LAST $XR0 109 
J 0
(-8877 2900);
DISPLAY 0.638298 (-8877 2900);
PAINT MONO (-8877 2900);
FORCEPROP 2 LAST CDS_LIB mstr_standard
J 0
(-8625 2900);
DISPLAY 0.808511 (-8625 2900);
DISPLAY INVISIBLE (-8625 2900);
FORCEPROP 1 LAST OFFPAGE TRUE
J 0
(-8300 2775);
DISPLAY 0.872340 (-8300 2775);
PAINT GREEN (-8300 2775);
DISPLAY INVISIBLE (-8300 2775);
FORCEPROP 1 LAST COMMENT_BODY TRUE
J 0
(-8500 2800);
DISPLAY 0.872340 (-8500 2800);
PAINT GREEN (-8500 2800);
DISPLAY INVISIBLE (-8500 2800);
FORCEPROP 2 LAST PATH I9
J 0
(-8875 2950);
DISPLAY 1.021277 (-8875 2950);
DISPLAY INVISIBLE (-8875 2950);
FORCEADD TAP..1
(-5950 3850);
FORCEPROP 3 LASTPIN (-6000 3850) SIG_NAME M_L_CPU1_SA_DQ<0>
J 0
(-5990 3860);
DISPLAY 0.659574 (-5990 3860);
PAINT MONO (-5990 3860);
DISPLAY INVISIBLE (-5990 3860);
FORCEPROP 1 LASTPIN (-6000 3850) BN 0
J 0
(-6012 3858);
DISPLAY 0.489362 (-6012 3858);
PAINT GREEN (-6012 3858);
FORCEPROP 2 LAST CDS_LIB mstr_standard
J 0
(-5950 3850);
DISPLAY 0.723404 (-5950 3850);
PAINT MONO (-5950 3850);
DISPLAY INVISIBLE (-5950 3850);
FORCEPROP 1 LAST BODY_TYPE PLUMBING
J 0
(-5950 3900);
DISPLAY 0.872340 (-5950 3900);
PAINT GREEN (-5950 3900);
DISPLAY INVISIBLE (-5950 3900);
FORCEPROP 1 LAST HDL_TAP TRUE
J 0
(-5625 3725);
DISPLAY 0.872340 (-5625 3725);
DISPLAY INVISIBLE (-5625 3725);
FORCEPROP 1 LAST PATH I90
J 0
(-5952 3850);
DISPLAY 0.872340 (-5952 3850);
PAINT GREEN (-5952 3850);
DISPLAY INVISIBLE (-5952 3850);
FORCEADD TAP..1
(-5950 3900);
FORCEPROP 3 LASTPIN (-6000 3900) SIG_NAME M_L_CPU1_SA_DQ<1>
J 0
(-5990 3910);
DISPLAY 0.659574 (-5990 3910);
PAINT MONO (-5990 3910);
DISPLAY INVISIBLE (-5990 3910);
FORCEPROP 1 LASTPIN (-6000 3900) BN 1
J 0
(-6012 3908);
DISPLAY 0.489362 (-6012 3908);
PAINT GREEN (-6012 3908);
FORCEPROP 2 LAST CDS_LIB mstr_standard
J 0
(-5950 3900);
DISPLAY 0.723404 (-5950 3900);
PAINT MONO (-5950 3900);
DISPLAY INVISIBLE (-5950 3900);
FORCEPROP 1 LAST BODY_TYPE PLUMBING
J 0
(-5950 3950);
DISPLAY 0.872340 (-5950 3950);
PAINT GREEN (-5950 3950);
DISPLAY INVISIBLE (-5950 3950);
FORCEPROP 1 LAST HDL_TAP TRUE
J 0
(-5625 3775);
DISPLAY 0.872340 (-5625 3775);
DISPLAY INVISIBLE (-5625 3775);
FORCEPROP 1 LAST PATH I91
J 0
(-5952 3900);
DISPLAY 0.872340 (-5952 3900);
PAINT GREEN (-5952 3900);
DISPLAY INVISIBLE (-5952 3900);
FORCEADD TAP..1
(-5950 3950);
FORCEPROP 3 LASTPIN (-6000 3950) SIG_NAME M_L_CPU1_SA_DQ<2>
J 0
(-5990 3960);
DISPLAY 0.659574 (-5990 3960);
PAINT MONO (-5990 3960);
DISPLAY INVISIBLE (-5990 3960);
FORCEPROP 1 LASTPIN (-6000 3950) BN 2
J 0
(-6012 3958);
DISPLAY 0.489362 (-6012 3958);
PAINT GREEN (-6012 3958);
FORCEPROP 2 LAST CDS_LIB mstr_standard
J 0
(-5950 3950);
DISPLAY 0.723404 (-5950 3950);
PAINT MONO (-5950 3950);
DISPLAY INVISIBLE (-5950 3950);
FORCEPROP 1 LAST BODY_TYPE PLUMBING
J 0
(-5950 4000);
DISPLAY 0.872340 (-5950 4000);
PAINT GREEN (-5950 4000);
DISPLAY INVISIBLE (-5950 4000);
FORCEPROP 1 LAST HDL_TAP TRUE
J 0
(-5625 3825);
DISPLAY 0.872340 (-5625 3825);
DISPLAY INVISIBLE (-5625 3825);
FORCEPROP 1 LAST PATH I92
J 0
(-5952 3950);
DISPLAY 0.872340 (-5952 3950);
PAINT GREEN (-5952 3950);
DISPLAY INVISIBLE (-5952 3950);
FORCEADD TAP..1
(-5950 3750);
FORCEPROP 3 LASTPIN (-6000 3750) SIG_NAME M_L_CPU1_SB_DQ<31>
J 0
(-5990 3760);
DISPLAY 0.659574 (-5990 3760);
PAINT MONO (-5990 3760);
DISPLAY INVISIBLE (-5990 3760);
FORCEPROP 1 LASTPIN (-6000 3750) BN 31
J 0
(-6012 3758);
DISPLAY 0.489362 (-6012 3758);
PAINT GREEN (-6012 3758);
FORCEPROP 2 LAST CDS_LIB mstr_standard
J 0
(-5950 3750);
DISPLAY 0.723404 (-5950 3750);
PAINT MONO (-5950 3750);
DISPLAY INVISIBLE (-5950 3750);
FORCEPROP 1 LAST BODY_TYPE PLUMBING
J 0
(-5950 3800);
DISPLAY 0.872340 (-5950 3800);
PAINT GREEN (-5950 3800);
DISPLAY INVISIBLE (-5950 3800);
FORCEPROP 1 LAST HDL_TAP TRUE
J 0
(-5625 3625);
DISPLAY 0.872340 (-5625 3625);
DISPLAY INVISIBLE (-5625 3625);
FORCEPROP 1 LAST PATH I93
J 0
(-5952 3750);
DISPLAY 0.872340 (-5952 3750);
PAINT GREEN (-5952 3750);
DISPLAY INVISIBLE (-5952 3750);
FORCEADD TAP..1
(-5950 3700);
FORCEPROP 3 LASTPIN (-6000 3700) SIG_NAME M_L_CPU1_SB_DQ<30>
J 0
(-5990 3710);
DISPLAY 0.659574 (-5990 3710);
PAINT MONO (-5990 3710);
DISPLAY INVISIBLE (-5990 3710);
FORCEPROP 1 LASTPIN (-6000 3700) BN 30
J 0
(-6012 3708);
DISPLAY 0.489362 (-6012 3708);
PAINT GREEN (-6012 3708);
FORCEPROP 2 LAST CDS_LIB mstr_standard
J 0
(-5950 3700);
DISPLAY 0.723404 (-5950 3700);
PAINT MONO (-5950 3700);
DISPLAY INVISIBLE (-5950 3700);
FORCEPROP 1 LAST BODY_TYPE PLUMBING
J 0
(-5950 3750);
DISPLAY 0.872340 (-5950 3750);
PAINT GREEN (-5950 3750);
DISPLAY INVISIBLE (-5950 3750);
FORCEPROP 1 LAST HDL_TAP TRUE
J 0
(-5625 3575);
DISPLAY 0.872340 (-5625 3575);
DISPLAY INVISIBLE (-5625 3575);
FORCEPROP 1 LAST PATH I94
J 0
(-5952 3700);
DISPLAY 0.872340 (-5952 3700);
PAINT GREEN (-5952 3700);
DISPLAY INVISIBLE (-5952 3700);
FORCEADD TAP..1
(-5950 4100);
FORCEPROP 3 LASTPIN (-6000 4100) SIG_NAME M_L_CPU1_SA_DQ<5>
J 0
(-5990 4110);
DISPLAY 0.659574 (-5990 4110);
PAINT MONO (-5990 4110);
DISPLAY INVISIBLE (-5990 4110);
FORCEPROP 1 LASTPIN (-6000 4100) BN 5
J 0
(-6012 4108);
DISPLAY 0.489362 (-6012 4108);
PAINT GREEN (-6012 4108);
FORCEPROP 2 LAST CDS_LIB mstr_standard
J 0
(-5950 4100);
DISPLAY 0.723404 (-5950 4100);
PAINT MONO (-5950 4100);
DISPLAY INVISIBLE (-5950 4100);
FORCEPROP 1 LAST BODY_TYPE PLUMBING
J 0
(-5950 4150);
DISPLAY 0.872340 (-5950 4150);
PAINT GREEN (-5950 4150);
DISPLAY INVISIBLE (-5950 4150);
FORCEPROP 1 LAST HDL_TAP TRUE
J 0
(-5625 3975);
DISPLAY 0.872340 (-5625 3975);
DISPLAY INVISIBLE (-5625 3975);
FORCEPROP 1 LAST PATH I95
J 0
(-5952 4100);
DISPLAY 0.872340 (-5952 4100);
PAINT GREEN (-5952 4100);
DISPLAY INVISIBLE (-5952 4100);
FORCEADD TAP..1
(-5950 4200);
FORCEPROP 3 LASTPIN (-6000 4200) SIG_NAME M_L_CPU1_SA_DQ<7>
J 0
(-5990 4210);
DISPLAY 0.659574 (-5990 4210);
PAINT MONO (-5990 4210);
DISPLAY INVISIBLE (-5990 4210);
FORCEPROP 1 LASTPIN (-6000 4200) BN 7
J 0
(-6012 4208);
DISPLAY 0.489362 (-6012 4208);
PAINT GREEN (-6012 4208);
FORCEPROP 2 LAST CDS_LIB mstr_standard
J 0
(-5950 4200);
DISPLAY 0.723404 (-5950 4200);
PAINT MONO (-5950 4200);
DISPLAY INVISIBLE (-5950 4200);
FORCEPROP 1 LAST BODY_TYPE PLUMBING
J 0
(-5950 4250);
DISPLAY 0.872340 (-5950 4250);
PAINT GREEN (-5950 4250);
DISPLAY INVISIBLE (-5950 4250);
FORCEPROP 1 LAST HDL_TAP TRUE
J 0
(-5625 4075);
DISPLAY 0.872340 (-5625 4075);
DISPLAY INVISIBLE (-5625 4075);
FORCEPROP 1 LAST PATH I96
J 0
(-5952 4200);
DISPLAY 0.872340 (-5952 4200);
PAINT GREEN (-5952 4200);
DISPLAY INVISIBLE (-5952 4200);
FORCEADD TAP..1
(-5950 4150);
FORCEPROP 3 LASTPIN (-6000 4150) SIG_NAME M_L_CPU1_SA_DQ<6>
J 0
(-5990 4160);
DISPLAY 0.659574 (-5990 4160);
PAINT MONO (-5990 4160);
DISPLAY INVISIBLE (-5990 4160);
FORCEPROP 1 LASTPIN (-6000 4150) BN 6
J 0
(-6012 4158);
DISPLAY 0.489362 (-6012 4158);
PAINT GREEN (-6012 4158);
FORCEPROP 2 LAST CDS_LIB mstr_standard
J 0
(-5950 4150);
DISPLAY 0.723404 (-5950 4150);
PAINT MONO (-5950 4150);
DISPLAY INVISIBLE (-5950 4150);
FORCEPROP 1 LAST BODY_TYPE PLUMBING
J 0
(-5950 4200);
DISPLAY 0.872340 (-5950 4200);
PAINT GREEN (-5950 4200);
DISPLAY INVISIBLE (-5950 4200);
FORCEPROP 1 LAST HDL_TAP TRUE
J 0
(-5625 4025);
DISPLAY 0.872340 (-5625 4025);
DISPLAY INVISIBLE (-5625 4025);
FORCEPROP 1 LAST PATH I97
J 0
(-5952 4150);
DISPLAY 0.872340 (-5952 4150);
PAINT GREEN (-5952 4150);
DISPLAY INVISIBLE (-5952 4150);
FORCEADD TAP..1
(-5950 4050);
FORCEPROP 3 LASTPIN (-6000 4050) SIG_NAME M_L_CPU1_SA_DQ<4>
J 0
(-5990 4060);
DISPLAY 0.659574 (-5990 4060);
PAINT MONO (-5990 4060);
DISPLAY INVISIBLE (-5990 4060);
FORCEPROP 1 LASTPIN (-6000 4050) BN 4
J 0
(-6012 4058);
DISPLAY 0.489362 (-6012 4058);
PAINT GREEN (-6012 4058);
FORCEPROP 2 LAST CDS_LIB mstr_standard
J 0
(-5950 4050);
DISPLAY 0.723404 (-5950 4050);
PAINT MONO (-5950 4050);
DISPLAY INVISIBLE (-5950 4050);
FORCEPROP 1 LAST BODY_TYPE PLUMBING
J 0
(-5950 4100);
DISPLAY 0.872340 (-5950 4100);
PAINT GREEN (-5950 4100);
DISPLAY INVISIBLE (-5950 4100);
FORCEPROP 1 LAST HDL_TAP TRUE
J 0
(-5625 3925);
DISPLAY 0.872340 (-5625 3925);
DISPLAY INVISIBLE (-5625 3925);
FORCEPROP 1 LAST PATH I98
J 0
(-5952 4050);
DISPLAY 0.872340 (-5952 4050);
PAINT GREEN (-5952 4050);
DISPLAY INVISIBLE (-5952 4050);
FORCEADD TAP..1
(-5950 4000);
FORCEPROP 3 LASTPIN (-6000 4000) SIG_NAME M_L_CPU1_SA_DQ<3>
J 0
(-5990 4010);
DISPLAY 0.659574 (-5990 4010);
PAINT MONO (-5990 4010);
DISPLAY INVISIBLE (-5990 4010);
FORCEPROP 1 LASTPIN (-6000 4000) BN 3
J 0
(-6012 4008);
DISPLAY 0.489362 (-6012 4008);
PAINT GREEN (-6012 4008);
FORCEPROP 2 LAST CDS_LIB mstr_standard
J 0
(-5950 4000);
DISPLAY 0.723404 (-5950 4000);
PAINT MONO (-5950 4000);
DISPLAY INVISIBLE (-5950 4000);
FORCEPROP 1 LAST BODY_TYPE PLUMBING
J 0
(-5950 4050);
DISPLAY 0.872340 (-5950 4050);
PAINT GREEN (-5950 4050);
DISPLAY INVISIBLE (-5950 4050);
FORCEPROP 1 LAST HDL_TAP TRUE
J 0
(-5625 3875);
DISPLAY 0.872340 (-5625 3875);
DISPLAY INVISIBLE (-5625 3875);
FORCEPROP 1 LAST PATH I99
J 0
(-5952 4000);
DISPLAY 0.872340 (-5952 4000);
PAINT GREEN (-5952 4000);
DISPLAY INVISIBLE (-5952 4000);
FORCEADD QUANTA_TITLE_BLOCK_C..1
(0 0);
FORCEPROP 0 LAST CDS_CON_LAST_MODIFIED Thu Sep 14 16:12:14 2023
J 0
(-1885 15);
DISPLAY INVISIBLE (-1885 15);
FORCEPROP 1 LAST CUSTOM_TXT_CDS <CON_LAST_MODIFIED>
J 0
(-1885 15);
DISPLAY 0.978723 (-1885 15);
FORCEPROP 2 LAST CUSTOM_TXT_CDS <XR_PAGE_TITLE>
J 0
(-7890 5250);
DISPLAY 0.638298 (-7890 5250);
PAINT PINK (-7890 5250);
DISPLAY INVISIBLE (-7890 5250);
FORCEPROP 1 LAST CUSTOM_TXT_CDS <NAME_2>
J 0
(-3175 50);
FORCEPROP 1 LAST CUSTOM_TXT_CDS <NAME_1>
J 0
(-3175 175);
FORCEPROP 1 LAST CUSTOM_TXT_CDS <Q_NUMBER>
J 0
(-1403 103);
DISPLAY 1.212766 (-1403 103);
FORCEPROP 1 LAST CUSTOM_TXT_CDS <Q_PROJ>
J 0
(-2382 102);
DISPLAY 1.212766 (-2382 102);
FORCEPROP 1 LAST CUSTOM_TXT_CDS <Q_REV>
J 0
(-184 103);
DISPLAY 1.212766 (-184 103);
FORCEPROP 1 LAST CUSTOM_TXT_CDS <CON_PAGE_NUM> OF <CON_TOTAL_PAGES>
J 0
(-446 18);
DISPLAY 0.978723 (-446 18);
FORCEPROP 1 LAST Q_TITLE DDR5 - CPU1 CHL
J 0
(-9275 75);
DISPLAY 2.446809 (-9275 75);
PAINT GREEN (-9275 75);
FORCEPROP 2 LAST CDS_LIB pure_quanta
J 0
(0 0);
DISPLAY INVISIBLE (0 0);
FORCEPROP 1 LAST CDS_LMAN_SYM_OUTLINE -9475,6775,100,-125
J 0
(0 0);
DISPLAY 0.468085 (0 0);
PAINT GREEN (0 0);
DISPLAY INVISIBLE (0 0);
FORCEPROP 2 LAST PAGE_BORDER TRUE
J 0
(-7890 5250);
DISPLAY 0.638298 (-7890 5250);
PAINT PINK (-7890 5250);
DISPLAY INVISIBLE (-7890 5250);
FORCEPROP 2 LAST CDS_XR_PAGE_TITLE CR-109 : @T6G_MB_LIB.T6G(SCH_1):PAGE109
J 0
(-7890 5250);
DISPLAY 0.638298 (-7890 5250);
PAINT PINK (-7890 5250);
DISPLAY INVISIBLE (-7890 5250);
FORCEPROP 1 LAST Q_DEPT BU9
J 1
(-3763 49);
DISPLAY 1.957447 (-3763 49);
PAINT GREEN (-3763 49);
DISPLAY INVISIBLE (-3763 49);
FORCEPROP 1 LAST COMMENT_BODY TRUE
J 0
(12 -13);
DISPLAY 0.978723 (12 -13);
PAINT GREEN (12 -13);
DISPLAY INVISIBLE (12 -13);
FORCEADD DNS..2
(-8300 2300);
PAINT RED (-8300 2300);
FORCEPROP 2 LAST CDS_LIB mstr_misc
J 0
(-8300 2300);
DISPLAY INVISIBLE (-8300 2300);
FORCEPROP 1 LAST COMMENT_BODY TRUE
R 1
J 0
(-8225 2075);
DISPLAY 0.872340 (-8225 2075);
PAINT PEACH (-8225 2075);
DISPLAY INVISIBLE (-8225 2075);
WIRE 17 -1 (-7700 3375)(-7700 3425);
WIRE 17 -1 (-7700 3325)(-7700 3375);
WIRE 17 -1 (-7700 3475)(-7700 3425);
WIRE 17 -1 (-7700 3475)(-7700 3525);
WIRE 17 -1 (-7700 3275)(-7700 3325);
WIRE 17 -1 (-7700 3225)(-7700 3275);
WIRE 17 -1 (-7700 3575)(-7700 3525);
WIRE 17 -1 (-7700 3575)(-7700 3600);
WIRE 17 -1 (-7700 3600)(-8200 3600);
FORCEPROP 2 LAST SIG_NAME M_L_CPU1_SB_CB<7:0>
J 0
(-8150 3610);
DISPLAY 0.489362 (-8150 3610);
WIRE 17 -1 (-7700 4025)(-7700 4050);
WIRE 17 -1 (-7700 4025)(-7700 3975);
WIRE 17 -1 (-7700 4050)(-8200 4050);
FORCEPROP 2 LAST SIG_NAME M_L_CPU1_SA_CB<7:0>
J 0
(-8150 4060);
DISPLAY 0.489362 (-8150 4060);
WIRE 17 -1 (-7700 3925)(-7700 3875);
WIRE 17 -1 (-7700 3925)(-7700 3975);
WIRE 17 -1 (-7700 3825)(-7700 3875);
WIRE 17 -1 (-7700 3775)(-7700 3825);
WIRE 17 -1 (-7700 3725)(-7700 3775);
WIRE 17 -1 (-7700 3675)(-7700 3725);
WIRE 17 -1 (-7700 5125)(-7700 5175);
WIRE 17 -1 (-7700 5175)(-7700 5225);
WIRE 17 -1 (-7700 5225)(-7700 5275);
WIRE 17 -1 (-7700 5275)(-7700 5325);
WIRE 17 -1 (-7700 5325)(-7700 5375);
WIRE 17 -1 (-7700 5375)(-7700 5425);
WIRE 17 -1 (-7700 5425)(-7700 5450);
WIRE 17 -1 (-7700 5450)(-8200 5450);
FORCEPROP 2 LAST SIG_NAME M_L_CPU1_SA_CA<6:0>
J 0
(-8185 5460);
DISPLAY 0.489362 (-8185 5460);
WIRE 17 -1 (-7700 4725)(-7700 4775);
WIRE 17 -1 (-7700 4775)(-7700 4825);
WIRE 17 -1 (-7700 4825)(-7700 4875);
WIRE 17 -1 (-7700 4875)(-7700 4925);
WIRE 17 -1 (-7700 4925)(-7700 4975);
WIRE 17 -1 (-7700 4975)(-7700 5025);
WIRE 17 -1 (-7700 5025)(-7700 5050);
WIRE 17 -1 (-7700 5050)(-8200 5050);
FORCEPROP 2 LAST SIG_NAME M_L_CPU1_SB_CA<6:0>
J 0
(-8185 5060);
DISPLAY 0.489362 (-8185 5060);
WIRE 17 -1 (-5900 4925)(-5900 4875);
WIRE 17 -1 (-5900 4975)(-5900 4925);
WIRE 17 -1 (-5900 4875)(-5900 4825);
WIRE 17 -1 (-5900 4825)(-5900 4775);
WIRE 17 -1 (-5900 5025)(-5900 4975);
WIRE 17 -1 (-5900 5075)(-5900 5025);
WIRE 17 -1 (-5900 4775)(-5900 4725);
WIRE 17 -1 (-5900 4725)(-5900 4675);
WIRE 17 -1 (-5900 5125)(-5900 5075);
WIRE 17 -1 (-5900 5175)(-5900 5125);
WIRE 17 -1 (-5900 4625)(-5900 4675);
WIRE 17 -1 (-5900 4575)(-5900 4625);
WIRE 17 -1 (-5900 5225)(-5900 5175);
WIRE 17 -1 (-5900 5275)(-5900 5225);
WIRE 17 -1 (-5900 4525)(-5900 4575);
WIRE 17 -1 (-5900 4475)(-5900 4525);
WIRE 17 -1 (-5900 5325)(-5900 5275);
WIRE 17 -1 (-5900 5375)(-5900 5325);
WIRE 17 -1 (-5900 4475)(-5900 4425);
WIRE 17 -1 (-5900 4425)(-5900 4375);
WIRE 17 -1 (-5900 5425)(-5900 5375);
WIRE 17 -1 (-5900 5450)(-5900 5425);
WIRE 17 -1 (-5900 4375)(-5900 4325);
WIRE 17 -1 (-5900 4325)(-5900 4275);
WIRE 17 -1 (-5900 5450)(-5325 5450);
FORCEPROP 2 LAST SIG_NAME M_L_CPU1_SA_DQ<31:0>
J 0
(-5835 5460);
DISPLAY 0.489362 (-5835 5460);
WIRE 17 -1 (-5900 4275)(-5900 4225);
WIRE 17 -1 (-5900 4225)(-5900 4175);
WIRE 17 -1 (-5900 4175)(-5900 4125);
WIRE 17 -1 (-5900 4125)(-5900 4075);
WIRE 17 -1 (-5900 4025)(-5900 4075);
WIRE 17 -1 (-5900 3975)(-5900 4025);
WIRE 17 -1 (-5900 3925)(-5900 3975);
WIRE 17 -1 (-5900 3875)(-5900 3925);
WIRE 17 -1 (-5900 3800)(-5900 3775);
WIRE 17 -1 (-5900 3800)(-5325 3800);
FORCEPROP 2 LAST SIG_NAME M_L_CPU1_SB_DQ<31:0>
J 0
(-5835 3810);
DISPLAY 0.489362 (-5835 3810);
WIRE 17 -1 (-5900 3775)(-5900 3725);
WIRE 17 -1 (-5900 3725)(-5900 3675);
WIRE 17 -1 (-5900 3675)(-5900 3625);
WIRE 17 -1 (-5900 3625)(-5900 3575);
WIRE 17 -1 (-5900 3575)(-5900 3525);
WIRE 17 -1 (-5900 3525)(-5900 3475);
WIRE 17 -1 (-5900 3475)(-5900 3425);
WIRE 17 -1 (-5900 3425)(-5900 3375);
WIRE 17 -1 (-5900 3375)(-5900 3325);
WIRE 17 -1 (-5900 3325)(-5900 3275);
WIRE 17 -1 (-5900 3275)(-5900 3225);
WIRE 17 -1 (-5900 3225)(-5900 3175);
WIRE 17 -1 (-5900 3175)(-5900 3125);
WIRE 17 -1 (-5900 3125)(-5900 3075);
WIRE 17 -1 (-5900 3075)(-5900 3025);
WIRE 17 -1 (-5900 2975)(-5900 3025);
WIRE 17 -1 (-5900 2925)(-5900 2975);
WIRE 17 -1 (-5900 2875)(-5900 2925);
WIRE 17 -1 (-5900 2825)(-5900 2875);
WIRE 17 -1 (-5900 2825)(-5900 2775);
WIRE 17 -1 (-5900 2775)(-5900 2725);
WIRE 17 -1 (-5900 2725)(-5900 2675);
WIRE 17 -1 (-5900 2675)(-5900 2625);
WIRE 17 -1 (-5900 2625)(-5900 2575);
WIRE 17 -1 (-5900 2575)(-5900 2525);
WIRE 17 -1 (-5900 2525)(-5900 2475);
WIRE 17 -1 (-5900 2475)(-5900 2425);
WIRE 17 -1 (-5900 2375)(-5900 2425);
WIRE 17 -1 (-5900 2325)(-5900 2375);
WIRE 17 -1 (-5900 2275)(-5900 2325);
WIRE 17 -1 (-5900 2225)(-5900 2275);
WIRE 17 -1 (-3150 4200)(-3150 4100);
WIRE 17 -1 (-3150 4300)(-3150 4200);
WIRE 17 -1 (-3150 4100)(-3150 4000);
WIRE 17 -1 (-3150 4000)(-3150 3900);
WIRE 17 -1 (-3150 4325)(-3150 4300);
WIRE 17 -1 (-3150 4325)(-2450 4325);
FORCEPROP 2 LAST SIG_NAME M_L_CPU1_SA_DQS_DN<9:0>
J 0
(-3085 4335);
DISPLAY 0.489362 (-3085 4335);
WIRE 17 -1 (-3350 4150)(-3350 4050);
WIRE 17 -1 (-3350 4250)(-3350 4150);
WIRE 17 -1 (-3350 4050)(-3350 3950);
WIRE 17 -1 (-3350 3850)(-3350 3950);
WIRE 17 -1 (-3350 4350)(-3350 4250);
WIRE 17 -1 (-3350 4375)(-3350 4350);
WIRE 17 -1 (-3350 3750)(-3350 3850);
WIRE 17 -1 (-3350 3650)(-3350 3750);
WIRE 17 -1 (-3350 4375)(-2450 4375);
FORCEPROP 2 LAST SIG_NAME M_L_CPU1_SA_DQS_DP<9:0>
J 0
(-3085 4385);
DISPLAY 0.489362 (-3085 4385);
WIRE 17 -1 (-3350 3300)(-3350 3200);
WIRE 17 -1 (-3350 3325)(-3350 3300);
WIRE 17 -1 (-3350 3200)(-3350 3100);
WIRE 17 -1 (-3350 3100)(-3350 3000);
WIRE 17 -1 (-3350 3325)(-2450 3325);
FORCEPROP 2 LAST SIG_NAME M_L_CPU1_SB_DQS_DP<9:0>
J 0
(-3085 3335);
DISPLAY 0.489362 (-3085 3335);
WIRE 17 -1 (-3150 3250)(-3150 3150);
WIRE 17 -1 (-3150 3275)(-3150 3250);
WIRE 17 -1 (-3150 3150)(-3150 3050);
WIRE 17 -1 (-3150 3050)(-3150 2950);
WIRE 17 -1 (-3150 3275)(-2450 3275);
FORCEPROP 2 LAST SIG_NAME M_L_CPU1_SB_DQS_DN<9:0>
J 0
(-3085 3285);
DISPLAY 0.489362 (-3085 3285);
WIRE 17 -1 (-3350 3000)(-3350 2900);
WIRE 17 -1 (-3150 3500)(-3150 3400);
WIRE 17 -1 (-3150 3600)(-3150 3500);
WIRE 17 -1 (-3150 3600)(-3150 3700);
WIRE 17 -1 (-3150 3700)(-3150 3800);
WIRE 17 -1 (-3150 3800)(-3150 3900);
WIRE 17 -1 (-3350 3550)(-3350 3450);
WIRE 17 -1 (-3350 3650)(-3350 3550);
WIRE 17 -1 (-3150 2450)(-3150 2350);
WIRE 17 -1 (-3150 2550)(-3150 2450);
WIRE 17 -1 (-3150 2550)(-3150 2650);
WIRE 17 -1 (-3150 2650)(-3150 2750);
WIRE 17 -1 (-3150 2750)(-3150 2850);
WIRE 17 -1 (-3150 2950)(-3150 2850);
WIRE 17 -1 (-3350 2500)(-3350 2400);
WIRE 17 -1 (-3350 2600)(-3350 2500);
WIRE 17 -1 (-3350 2600)(-3350 2700);
WIRE 17 -1 (-3350 2700)(-3350 2800);
WIRE 17 -1 (-3350 2800)(-3350 2900);
WIRE 16 -1 (-6350 950)(-6350 1025);
WIRE 16 -1 (-8575 3050)(-8575 3125);
WIRE 16 -1 (-8325 2400)(-8325 2425);
WIRE 16 -1 (-6000 4550)(-6200 4550);
WIRE 16 -1 (-6200 4600)(-6000 4600);
WIRE 16 -1 (-3600 3275)(-3450 3275);
WIRE 16 -1 (-3600 3225)(-3250 3225);
WIRE 16 -1 (-3600 4325)(-3450 4325);
WIRE 16 -1 (-3600 4275)(-3250 4275);
WIRE 16 -1 (-3450 4225)(-3600 4225);
WIRE 16 -1 (-3600 4175)(-3250 4175);
WIRE 16 -1 (-3600 3025)(-3250 3025);
WIRE 16 -1 (-3450 4125)(-3600 4125);
WIRE 16 -1 (-3450 2975)(-3600 2975);
WIRE 16 -1 (-3600 2925)(-3250 2925);
WIRE 16 -1 (-3600 3975)(-3250 3975);
WIRE 16 -1 (-3600 2875)(-3450 2875);
WIRE 16 -1 (-3600 2825)(-3250 2825);
WIRE 16 -1 (-3600 3925)(-3450 3925);
WIRE 16 -1 (-3600 3875)(-3250 3875);
WIRE 16 -1 (-3450 2775)(-3600 2775);
WIRE 16 -1 (-3600 2725)(-3250 2725);
WIRE 16 -1 (-3450 3825)(-3600 3825);
WIRE 16 -1 (-3600 3775)(-3250 3775);
WIRE 16 -1 (-3450 2675)(-3600 2675);
WIRE 16 -1 (-3600 2625)(-3250 2625);
WIRE 16 -1 (-3450 3725)(-3600 3725);
WIRE 16 -1 (-3600 3675)(-3250 3675);
WIRE 16 -1 (-3450 2575)(-3600 2575);
WIRE 16 -1 (-3600 2525)(-3250 2525);
WIRE 16 -1 (-3450 3625)(-3600 3625);
WIRE 16 -1 (-3600 3575)(-3250 3575);
WIRE 16 -1 (-3600 2475)(-3450 2475);
WIRE 16 -1 (-3600 2425)(-3250 2425);
WIRE 16 -1 (-3600 3525)(-3450 3525);
WIRE 16 -1 (-3600 3475)(-3250 3475);
WIRE 16 -1 (-3450 2375)(-3600 2375);
WIRE 16 -1 (-3600 2325)(-3250 2325);
WIRE 16 -1 (-3450 3425)(-3600 3425);
WIRE 16 -1 (-3600 3375)(-3250 3375);
WIRE 16 -1 (-3450 3075)(-3600 3075);
WIRE 16 -1 (-3600 3125)(-3250 3125);
WIRE 16 -1 (-3450 3175)(-3600 3175);
WIRE 16 -1 (-3450 4025)(-3600 4025);
WIRE 16 -1 (-3600 4075)(-3250 4075);
WIRE 16 -1 (-6000 4900)(-6200 4900);
WIRE 16 -1 (-6000 4950)(-6200 4950);
WIRE 16 -1 (-6200 5000)(-6000 5000);
WIRE 16 -1 (-6000 5050)(-6200 5050);
WIRE 16 -1 (-6000 5100)(-6200 5100);
WIRE 16 -1 (-6000 5150)(-6200 5150);
WIRE 16 -1 (-6200 5200)(-6000 5200);
WIRE 16 -1 (-6000 5250)(-6200 5250);
WIRE 16 -1 (-6000 5300)(-6200 5300);
WIRE 16 -1 (-6000 5350)(-6200 5350);
WIRE 16 -1 (-6200 5400)(-6000 5400);
WIRE 16 -1 (-7400 4600)(-8200 4600);
FORCEPROP 2 LAST SIG_NAME M_L_CPU1_SA_PAR
J 0
(-8150 4610);
DISPLAY 0.489362 (-8150 4610);
WIRE 16 -1 (-7400 1950)(-8200 1950);
FORCEPROP 2 LAST SIG_NAME M_L_CPU1_SB_RSP<0>
J 0
(-8150 1960);
DISPLAY 0.489362 (-8150 1960);
WIRE 16 -1 (-6000 2200)(-6200 2200);
WIRE 16 -1 (-6000 2250)(-6200 2250);
WIRE 16 -1 (-6000 2300)(-6200 2300);
WIRE 16 -1 (-6200 2350)(-6000 2350);
WIRE 16 -1 (-6000 2400)(-6200 2400);
WIRE 16 -1 (-6000 2450)(-6200 2450);
WIRE 16 -1 (-6000 2500)(-6200 2500);
WIRE 16 -1 (-6200 2550)(-6000 2550);
WIRE 16 -1 (-6000 2600)(-6200 2600);
WIRE 16 -1 (-6000 2650)(-6200 2650);
WIRE 16 -1 (-6000 2700)(-6200 2700);
WIRE 16 -1 (-6200 2750)(-6000 2750);
WIRE 16 -1 (-6000 2800)(-6200 2800);
WIRE 16 -1 (-6000 2850)(-6200 2850);
WIRE 16 -1 (-6000 2900)(-6200 2900);
WIRE 16 -1 (-6200 2950)(-6000 2950);
WIRE 16 -1 (-6000 3000)(-6200 3000);
WIRE 16 -1 (-6000 3050)(-6200 3050);
WIRE 16 -1 (-6000 3100)(-6200 3100);
WIRE 16 -1 (-6200 3150)(-6000 3150);
WIRE 16 -1 (-6000 3200)(-6200 3200);
WIRE 16 -1 (-6000 3250)(-6200 3250);
WIRE 16 -1 (-6000 3300)(-6200 3300);
WIRE 16 -1 (-6200 3350)(-6000 3350);
WIRE 16 -1 (-6000 3400)(-6200 3400);
WIRE 16 -1 (-6000 3450)(-6200 3450);
WIRE 16 -1 (-6000 3500)(-6200 3500);
WIRE 16 -1 (-6200 3550)(-6000 3550);
WIRE 16 -1 (-6000 3600)(-6200 3600);
WIRE 16 -1 (-6000 3650)(-6200 3650);
WIRE 16 -1 (-6000 3700)(-6200 3700);
WIRE 16 -1 (-6200 3750)(-6000 3750);
WIRE 16 -1 (-6000 3850)(-6200 3850);
WIRE 16 -1 (-6000 3900)(-6200 3900);
WIRE 16 -1 (-6000 3950)(-6200 3950);
WIRE 16 -1 (-6200 4000)(-6000 4000);
WIRE 16 -1 (-6000 4050)(-6200 4050);
WIRE 16 -1 (-6000 4100)(-6200 4100);
WIRE 16 -1 (-6000 4150)(-6200 4150);
WIRE 16 -1 (-6200 4200)(-6000 4200);
WIRE 16 -1 (-6000 4250)(-6200 4250);
WIRE 16 -1 (-6000 4300)(-6200 4300);
WIRE 16 -1 (-6000 4350)(-6200 4350);
WIRE 16 -1 (-6200 4400)(-6000 4400);
WIRE 16 -1 (-6000 4450)(-6200 4450);
WIRE 16 -1 (-6000 4500)(-6200 4500);
WIRE 16 -1 (-6000 4650)(-6200 4650);
WIRE 16 -1 (-6000 4700)(-6200 4700);
WIRE 16 -1 (-6000 4750)(-6200 4750);
WIRE 16 -1 (-6200 4800)(-6000 4800);
WIRE 16 -1 (-6000 4850)(-6200 4850);
WIRE 16 -1 (-7400 4450)(-8200 4450);
FORCEPROP 2 LAST SIG_NAME M_L_CPU1_SA_CS_N<1>
J 0
(-8150 4460);
DISPLAY 0.489362 (-8150 4460);
WIRE 16 -1 (-7400 4250)(-8200 4250);
FORCEPROP 2 LAST SIG_NAME M_L_CPU1_SB_CS_N<0>
J 0
(-8150 4260);
DISPLAY 0.489362 (-8150 4260);
WIRE 16 -1 (-7400 4150)(-8200 4150);
FORCEPROP 2 LAST SIG_NAME M_L_CPU1_CLK_DP<0>
J 0
(-8150 4160);
DISPLAY 0.489362 (-8150 4160);
WIRE 16 -1 (-7400 4100)(-8200 4100);
FORCEPROP 2 LAST SIG_NAME M_L_CPU1_CLK_DN<0>
J 0
(-8150 4110);
DISPLAY 0.489362 (-8150 4110);
WIRE 16 -1 (-7400 3200)(-7600 3200);
WIRE 16 -1 (-7400 3250)(-7600 3250);
WIRE 16 -1 (-7400 3300)(-7600 3300);
WIRE 16 -1 (-7400 3400)(-7600 3400);
WIRE 16 -1 (-7400 3450)(-7600 3450);
WIRE 16 -1 (-7400 3500)(-7600 3500);
WIRE 16 -1 (-7400 3650)(-7600 3650);
WIRE 16 -1 (-7400 3750)(-7600 3750);
WIRE 16 -1 (-7400 3800)(-7600 3800);
WIRE 16 -1 (-7400 3900)(-7600 3900);
WIRE 16 -1 (-7400 3950)(-7600 3950);
WIRE 16 -1 (-7400 5000)(-7600 5000);
WIRE 16 -1 (-7400 5400)(-7600 5400);
WIRE 16 -1 (-7400 4950)(-7600 4950);
WIRE 16 -1 (-7400 5350)(-7600 5350);
WIRE 16 -1 (-7400 4900)(-7600 4900);
WIRE 16 -1 (-7400 5300)(-7600 5300);
WIRE 16 -1 (-7400 4850)(-7600 4850);
WIRE 16 -1 (-7400 5250)(-7600 5250);
WIRE 16 -1 (-7400 4800)(-7600 4800);
WIRE 16 -1 (-7400 5200)(-7600 5200);
WIRE 16 -1 (-7400 4750)(-7600 4750);
WIRE 16 -1 (-7400 5150)(-7600 5150);
WIRE 16 -1 (-7400 4700)(-7600 4700);
WIRE 16 -1 (-7400 5100)(-7600 5100);
WIRE 16 -1 (-7400 3550)(-7600 3550);
WIRE 16 -1 (-7400 3700)(-7600 3700);
WIRE 16 -1 (-7400 3850)(-7600 3850);
WIRE 16 -1 (-7400 4000)(-7600 4000);
WIRE 16 -1 (-6350 1300)(-6350 1225);
WIRE 16 -1 (-6350 1300)(-7075 1300);
FORCEPROP 2 LAST SIG_NAME PD_CHL_CPU1_DIMM_SAA
J 0
(-7060 1310);
DISPLAY 0.489362 (-7060 1310);
WIRE 16 -1 (-7400 4300)(-8200 4300);
FORCEPROP 2 LAST SIG_NAME M_L_CPU1_SB_CS_N<1>
J 0
(-8150 4310);
DISPLAY 0.489362 (-8150 4310);
WIRE 16 -1 (-7400 4400)(-8200 4400);
FORCEPROP 2 LAST SIG_NAME M_L_CPU1_SA_CS_N<0>
J 0
(-8150 4410);
DISPLAY 0.489362 (-8150 4410);
WIRE 16 -1 (-7400 4550)(-8200 4550);
FORCEPROP 2 LAST SIG_NAME M_L_CPU1_SB_PAR
J 0
(-8150 4560);
DISPLAY 0.489362 (-8150 4560);
WIRE 16 -1 (-7400 3350)(-7600 3350);
WIRE 16 -1 (-7400 2000)(-8200 2000);
FORCEPROP 2 LAST SIG_NAME M_L_CPU1_SA_RSP<0>
J 0
(-8150 2010);
DISPLAY 0.489362 (-8150 2010);
WIRE 16 -1 (-8550 2150)(-8950 2150);
FORCEPROP 2 LAST SIG_NAME PWRGD_CHGL_CPU1
J 0
(-8910 2160);
DISPLAY 0.489362 (-8910 2160);
WIRE 16 -1 (-7400 3100)(-8050 3100);
FORCEPROP 2 LAST SIG_NAME M_L_CPU1_RESET_N
J 0
(-8035 3110);
DISPLAY 0.489362 (-8035 3110);
WIRE 16 -1 (-7400 3050)(-8050 3050);
FORCEPROP 2 LAST SIG_NAME M_L_CPU1_ALERT_N
J 0
(-8035 3060);
DISPLAY 0.489362 (-8035 3060);
WIRE 16 -1 (-2100 5225)(-1800 5225);
WIRE 16 -1 (-2100 5275)(-2100 5225);
WIRE 16 -1 (-1800 5275)(-2100 5275);
WIRE 16 -1 (-2100 5275)(-2100 5325);
WIRE 16 -1 (-1800 5325)(-2100 5325);
WIRE 16 -1 (-2100 5325)(-2100 6050);
WIRE 16 -1 (-2225 6050)(-2100 6050);
WIRE 16 -1 (-2225 6050)(-2225 5950);
WIRE 16 -1 (-2225 6050)(-2800 6050);
WIRE 16 -1 (-2800 5950)(-2800 6050);
WIRE 16 -1 (-2800 6050)(-2800 6125);
WIRE 16 -1 (-2225 5625)(-2225 5750);
WIRE 16 -1 (-2225 5625)(-2800 5625);
WIRE 16 -1 (-2800 5625)(-2800 5750);
WIRE 16 -1 (-2800 5625)(-2800 5550);
WIRE 16 -1 (-300 5325)(-300 5275);
WIRE 16 -1 (-300 5325)(-600 5325);
WIRE 16 -1 (-300 5275)(-300 5225);
WIRE 16 -1 (-300 5275)(-600 5275);
WIRE 16 -1 (-300 5225)(-300 5175);
WIRE 16 -1 (-300 5225)(-600 5225);
WIRE 16 -1 (-300 5175)(-300 5125);
WIRE 16 -1 (-300 5175)(-600 5175);
WIRE 16 -1 (-300 5125)(-600 5125);
WIRE 16 -1 (-300 5125)(-300 5075);
WIRE 16 -1 (-300 5075)(-300 5025);
WIRE 16 -1 (-300 5075)(-600 5075);
WIRE 16 -1 (-300 5025)(-300 4975);
WIRE 16 -1 (-300 5025)(-600 5025);
WIRE 16 -1 (-300 4975)(-300 4925);
WIRE 16 -1 (-300 4975)(-600 4975);
WIRE 16 -1 (-300 4925)(-300 4875);
WIRE 16 -1 (-300 4925)(-600 4925);
WIRE 16 -1 (-300 4875)(-300 4825);
WIRE 16 -1 (-300 4875)(-600 4875);
WIRE 16 -1 (-300 4825)(-300 4775);
WIRE 16 -1 (-300 4825)(-600 4825);
WIRE 16 -1 (-300 4775)(-300 4725);
WIRE 16 -1 (-300 4775)(-600 4775);
WIRE 16 -1 (-300 4725)(-300 4675);
WIRE 16 -1 (-300 4725)(-600 4725);
WIRE 16 -1 (-300 4675)(-300 4625);
WIRE 16 -1 (-300 4675)(-600 4675);
WIRE 16 -1 (-300 4625)(-300 4575);
WIRE 16 -1 (-300 4625)(-600 4625);
WIRE 16 -1 (-300 4575)(-300 4525);
WIRE 16 -1 (-300 4575)(-600 4575);
WIRE 16 -1 (-300 4525)(-300 4475);
WIRE 16 -1 (-300 4525)(-600 4525);
WIRE 16 -1 (-300 4475)(-300 4425);
WIRE 16 -1 (-300 4475)(-600 4475);
WIRE 16 -1 (-300 4425)(-300 4375);
WIRE 16 -1 (-300 4425)(-600 4425);
WIRE 16 -1 (-300 4375)(-300 4325);
WIRE 16 -1 (-300 4375)(-600 4375);
WIRE 16 -1 (-300 4325)(-300 4275);
WIRE 16 -1 (-300 4325)(-600 4325);
WIRE 16 -1 (-300 4275)(-300 4225);
WIRE 16 -1 (-300 4275)(-600 4275);
WIRE 16 -1 (-300 4225)(-300 4175);
WIRE 16 -1 (-300 4225)(-600 4225);
WIRE 16 -1 (-300 4175)(-300 4125);
WIRE 16 -1 (-300 4175)(-600 4175);
WIRE 16 -1 (-300 4125)(-600 4125);
WIRE 16 -1 (-300 4125)(-300 4075);
WIRE 16 -1 (-300 4075)(-300 4025);
WIRE 16 -1 (-300 4075)(-600 4075);
WIRE 16 -1 (-300 4025)(-300 3975);
WIRE 16 -1 (-300 4025)(-600 4025);
WIRE 16 -1 (-300 3975)(-300 3925);
WIRE 16 -1 (-300 3975)(-600 3975);
WIRE 16 -1 (-300 3925)(-300 3875);
WIRE 16 -1 (-300 3925)(-600 3925);
WIRE 16 -1 (-300 3875)(-300 3825);
WIRE 16 -1 (-300 3875)(-600 3875);
WIRE 16 -1 (-300 3825)(-300 3775);
WIRE 16 -1 (-300 3825)(-600 3825);
WIRE 16 -1 (-300 3775)(-300 3725);
WIRE 16 -1 (-300 3775)(-600 3775);
WIRE 16 -1 (-300 3725)(-300 3675);
WIRE 16 -1 (-300 3725)(-600 3725);
WIRE 16 -1 (-300 3675)(-300 3625);
WIRE 16 -1 (-300 3675)(-600 3675);
WIRE 16 -1 (-300 3625)(-300 3575);
WIRE 16 -1 (-300 3625)(-600 3625);
WIRE 16 -1 (-300 3575)(-300 3525);
WIRE 16 -1 (-300 3575)(-600 3575);
WIRE 16 -1 (-300 3525)(-300 3475);
WIRE 16 -1 (-300 3525)(-600 3525);
WIRE 16 -1 (-300 3475)(-300 3425);
WIRE 16 -1 (-300 3475)(-600 3475);
WIRE 16 -1 (-300 3425)(-300 3375);
WIRE 16 -1 (-300 3425)(-600 3425);
WIRE 16 -1 (-300 3375)(-300 3325);
WIRE 16 -1 (-300 3375)(-600 3375);
WIRE 16 -1 (-300 3325)(-300 3275);
WIRE 16 -1 (-300 3325)(-600 3325);
WIRE 16 -1 (-300 3275)(-300 3225);
WIRE 16 -1 (-300 3275)(-600 3275);
WIRE 16 -1 (-300 3225)(-300 3175);
WIRE 16 -1 (-300 3225)(-600 3225);
WIRE 16 -1 (-300 3175)(-300 3125);
WIRE 16 -1 (-300 3175)(-600 3175);
WIRE 16 -1 (-300 3125)(-300 3075);
WIRE 16 -1 (-300 3125)(-600 3125);
WIRE 16 -1 (-300 3075)(-600 3075);
WIRE 16 -1 (-300 3075)(-300 3025);
WIRE 16 -1 (-300 3025)(-300 2975);
WIRE 16 -1 (-300 3025)(-600 3025);
WIRE 16 -1 (-300 2975)(-300 2925);
WIRE 16 -1 (-300 2975)(-600 2975);
WIRE 16 -1 (-300 2925)(-300 2875);
WIRE 16 -1 (-300 2925)(-600 2925);
WIRE 16 -1 (-300 2875)(-300 2825);
WIRE 16 -1 (-300 2875)(-600 2875);
WIRE 16 -1 (-300 2825)(-300 2775);
WIRE 16 -1 (-300 2825)(-600 2825);
WIRE 16 -1 (-300 2775)(-300 2725);
WIRE 16 -1 (-300 2775)(-600 2775);
WIRE 16 -1 (-300 2725)(-300 2675);
WIRE 16 -1 (-300 2725)(-600 2725);
WIRE 16 -1 (-300 2675)(-300 2625);
WIRE 16 -1 (-300 2675)(-600 2675);
WIRE 16 -1 (-300 2625)(-300 2575);
WIRE 16 -1 (-300 2625)(-600 2625);
WIRE 16 -1 (-300 2575)(-300 2525);
WIRE 16 -1 (-300 2575)(-600 2575);
WIRE 16 -1 (-300 2525)(-300 2475);
WIRE 16 -1 (-300 2525)(-600 2525);
WIRE 16 -1 (-300 2475)(-300 2425);
WIRE 16 -1 (-300 2475)(-600 2475);
WIRE 16 -1 (-300 2425)(-300 2375);
WIRE 16 -1 (-300 2425)(-600 2425);
WIRE 16 -1 (-300 2375)(-300 2325);
WIRE 16 -1 (-300 2375)(-600 2375);
WIRE 16 -1 (-300 2325)(-300 2275);
WIRE 16 -1 (-300 2325)(-600 2325);
WIRE 16 -1 (-300 2275)(-300 2225);
WIRE 16 -1 (-300 2275)(-600 2275);
WIRE 16 -1 (-300 2225)(-300 2175);
WIRE 16 -1 (-300 2225)(-600 2225);
WIRE 16 -1 (-300 2175)(-300 2075);
WIRE 16 -1 (-300 2175)(-600 2175);
WIRE 16 -1 (-300 2075)(-600 2075);
WIRE 16 -1 (-300 2075)(-300 2025);
WIRE 16 -1 (-300 2025)(-300 1975);
WIRE 16 -1 (-300 2025)(-600 2025);
WIRE 16 -1 (-300 1975)(-300 1725);
WIRE 16 -1 (-300 1975)(-600 1975);
WIRE 16 -1 (-1800 5175)(-2100 5175);
WIRE 16 -1 (-2100 5175)(-2100 5125);
WIRE 16 -1 (-1800 5125)(-2100 5125);
WIRE 16 -1 (-2100 5125)(-2100 5075);
WIRE 16 -1 (-1800 5075)(-2100 5075);
WIRE 16 -1 (-2100 5075)(-2100 5025);
WIRE 16 -1 (-1800 5025)(-2100 5025);
WIRE 16 -1 (-2100 5025)(-2100 4975);
WIRE 16 -1 (-1800 4975)(-2100 4975);
WIRE 16 -1 (-2100 4975)(-2100 4925);
WIRE 16 -1 (-1800 4925)(-2100 4925);
WIRE 16 -1 (-2100 4925)(-2100 4875);
WIRE 16 -1 (-1800 4875)(-2100 4875);
WIRE 16 -1 (-2100 4875)(-2100 4825);
WIRE 16 -1 (-1800 4825)(-2100 4825);
WIRE 16 -1 (-2100 4825)(-2100 4775);
WIRE 16 -1 (-1800 4775)(-2100 4775);
WIRE 16 -1 (-2100 4775)(-2100 4725);
WIRE 16 -1 (-1800 4725)(-2100 4725);
WIRE 16 -1 (-2100 4725)(-2100 4675);
WIRE 16 -1 (-1800 4675)(-2100 4675);
WIRE 16 -1 (-2100 4675)(-2100 4625);
WIRE 16 -1 (-1800 4625)(-2100 4625);
WIRE 16 -1 (-2100 4625)(-2100 4575);
WIRE 16 -1 (-1800 4575)(-2100 4575);
WIRE 16 -1 (-2100 4575)(-2100 4525);
WIRE 16 -1 (-1800 4525)(-2100 4525);
WIRE 16 -1 (-2100 4525)(-2100 4475);
WIRE 16 -1 (-1800 4475)(-2100 4475);
WIRE 16 -1 (-2100 4475)(-2100 4425);
WIRE 16 -1 (-1800 4425)(-2100 4425);
WIRE 16 -1 (-2100 4425)(-2100 4375);
WIRE 16 -1 (-1800 4375)(-2100 4375);
WIRE 16 -1 (-2100 4375)(-2100 4325);
WIRE 16 -1 (-1800 4325)(-2100 4325);
WIRE 16 -1 (-2100 4325)(-2100 4275);
WIRE 16 -1 (-1800 4275)(-2100 4275);
WIRE 16 -1 (-2100 4275)(-2100 4225);
WIRE 16 -1 (-1800 4225)(-2100 4225);
WIRE 16 -1 (-2100 4225)(-2100 4175);
WIRE 16 -1 (-1800 4175)(-2100 4175);
WIRE 16 -1 (-2100 4175)(-2100 4125);
WIRE 16 -1 (-1800 4125)(-2100 4125);
WIRE 16 -1 (-2100 4125)(-2100 4075);
WIRE 16 -1 (-1800 4075)(-2100 4075);
WIRE 16 -1 (-2100 4075)(-2100 4025);
WIRE 16 -1 (-1800 4025)(-2100 4025);
WIRE 16 -1 (-2100 4025)(-2100 3975);
WIRE 16 -1 (-1800 3975)(-2100 3975);
WIRE 16 -1 (-2100 3975)(-2100 3925);
WIRE 16 -1 (-1800 3925)(-2100 3925);
WIRE 16 -1 (-2100 3925)(-2100 3875);
WIRE 16 -1 (-1800 3875)(-2100 3875);
WIRE 16 -1 (-2100 3875)(-2100 3825);
WIRE 16 -1 (-1800 3825)(-2100 3825);
WIRE 16 -1 (-2100 3825)(-2100 3775);
WIRE 16 -1 (-1800 3775)(-2100 3775);
WIRE 16 -1 (-2100 3775)(-2100 3725);
WIRE 16 -1 (-1800 3725)(-2100 3725);
WIRE 16 -1 (-2100 3725)(-2100 3675);
WIRE 16 -1 (-1800 3675)(-2100 3675);
WIRE 16 -1 (-2100 3675)(-2100 3625);
WIRE 16 -1 (-1800 3625)(-2100 3625);
WIRE 16 -1 (-2100 3625)(-2100 3575);
WIRE 16 -1 (-1800 3575)(-2100 3575);
WIRE 16 -1 (-2100 3575)(-2100 3525);
WIRE 16 -1 (-1800 3525)(-2100 3525);
WIRE 16 -1 (-2100 3525)(-2100 3475);
WIRE 16 -1 (-1800 3475)(-2100 3475);
WIRE 16 -1 (-2100 3475)(-2100 3425);
WIRE 16 -1 (-1800 3425)(-2100 3425);
WIRE 16 -1 (-2100 3425)(-2100 3375);
WIRE 16 -1 (-1800 3375)(-2100 3375);
WIRE 16 -1 (-2100 3375)(-2100 3325);
WIRE 16 -1 (-1800 3325)(-2100 3325);
WIRE 16 -1 (-2100 3325)(-2100 3275);
WIRE 16 -1 (-1800 3275)(-2100 3275);
WIRE 16 -1 (-2100 3275)(-2100 3225);
WIRE 16 -1 (-1800 3225)(-2100 3225);
WIRE 16 -1 (-2100 3225)(-2100 3175);
WIRE 16 -1 (-1800 3175)(-2100 3175);
WIRE 16 -1 (-2100 3175)(-2100 3125);
WIRE 16 -1 (-1800 3125)(-2100 3125);
WIRE 16 -1 (-2100 3125)(-2100 3075);
WIRE 16 -1 (-1800 3075)(-2100 3075);
WIRE 16 -1 (-2100 3075)(-2100 3025);
WIRE 16 -1 (-1800 3025)(-2100 3025);
WIRE 16 -1 (-2100 3025)(-2100 2975);
WIRE 16 -1 (-1800 2975)(-2100 2975);
WIRE 16 -1 (-2100 2975)(-2100 2925);
WIRE 16 -1 (-1800 2925)(-2100 2925);
WIRE 16 -1 (-2100 2925)(-2100 2875);
WIRE 16 -1 (-1800 2875)(-2100 2875);
WIRE 16 -1 (-2100 2875)(-2100 2825);
WIRE 16 -1 (-1800 2825)(-2100 2825);
WIRE 16 -1 (-2100 2825)(-2100 2775);
WIRE 16 -1 (-1800 2775)(-2100 2775);
WIRE 16 -1 (-2100 2775)(-2100 2725);
WIRE 16 -1 (-1800 2725)(-2100 2725);
WIRE 16 -1 (-2100 2725)(-2100 2675);
WIRE 16 -1 (-1800 2675)(-2100 2675);
WIRE 16 -1 (-2100 2675)(-2100 2625);
WIRE 16 -1 (-1800 2625)(-2100 2625);
WIRE 16 -1 (-2100 2625)(-2100 2575);
WIRE 16 -1 (-1800 2575)(-2100 2575);
WIRE 16 -1 (-2100 2575)(-2100 2525);
WIRE 16 -1 (-1800 2525)(-2100 2525);
WIRE 16 -1 (-2100 2525)(-2100 2475);
WIRE 16 -1 (-1800 2475)(-2100 2475);
WIRE 16 -1 (-2100 2475)(-2100 2425);
WIRE 16 -1 (-1800 2425)(-2100 2425);
WIRE 16 -1 (-2100 2425)(-2100 2375);
WIRE 16 -1 (-1800 2375)(-2100 2375);
WIRE 16 -1 (-2100 2375)(-2100 2325);
WIRE 16 -1 (-1800 2325)(-2100 2325);
WIRE 16 -1 (-2100 2325)(-2100 2275);
WIRE 16 -1 (-1800 2275)(-2100 2275);
WIRE 16 -1 (-2100 2275)(-2100 2225);
WIRE 16 -1 (-1800 2225)(-2100 2225);
WIRE 16 -1 (-2100 2225)(-2100 2175);
WIRE 16 -1 (-1800 2175)(-2100 2175);
WIRE 16 -1 (-2100 2175)(-2100 2125);
WIRE 16 -1 (-1800 2125)(-2100 2125);
WIRE 16 -1 (-2100 2125)(-2100 2075);
WIRE 16 -1 (-1800 2075)(-2100 2075);
WIRE 16 -1 (-2100 2075)(-2100 1950);
WIRE 16 -1 (-7400 2850)(-7975 2850);
FORCEPROP 2 LAST SIG_NAME I3C_SPD_DDRL_CPU1_SDA
J 0
(-7885 2860);
DISPLAY 0.446809 (-7885 2860);
FORCEPROP 2 LASTPROP $XRERR UNIQUE?
J 0
(-8125 2860);
DISPLAY 0.638298 (-8125 2860);
PAINT MONO (-8125 2860);
DISPLAY INVISIBLE (-8125 2860);
WIRE 16 -1 (-7500 2625)(-7600 2625);
WIRE 16 -1 (-7500 2800)(-7500 2625);
WIRE 16 -1 (-7400 2800)(-7500 2800);
FORCEPROP 2 LAST SIG_NAME I3C_SPD_DDRL_CPU1_SCL
J 0
(-7885 2810);
DISPLAY 0.446809 (-7885 2810);
FORCEPROP 2 LASTPROP $XRERR UNIQUE?
J 0
(-8125 2810);
DISPLAY 0.638298 (-8125 2810);
PAINT MONO (-8125 2810);
DISPLAY INVISIBLE (-8125 2810);
WIRE 16 -1 (-8100 2150)(-8100 2550);
WIRE 16 -1 (-8100 2150)(-8325 2150);
WIRE 16 -1 (-7400 2550)(-8100 2550);
FORCEPROP 2 LAST SIG_NAME PWRGD_CHL_CPU1_DIMM
J 0
(-7975 2560);
DISPLAY 0.489362 (-7975 2560);
FORCEPROP 2 LASTPROP $XRERR UNIQUE?
J 0
(-8215 2560);
DISPLAY 0.638298 (-8215 2560);
PAINT MONO (-8215 2560);
DISPLAY INVISIBLE (-8215 2560);
WIRE 16 -1 (-8325 2200)(-8325 2150);
WIRE 16 -1 (-8325 2150)(-8350 2150);
WIRE 16 -1 (-7800 2625)(-8225 2625);
FORCEPROP 2 LAST SIG_NAME I3C_SPD_DDRGL_CPU1_SCL
J 0
(-8285 2635);
DISPLAY 0.489362 (-8285 2635);
WIRE 16 -1 (-8200 2850)(-8175 2850);
WIRE 16 -1 (-8200 2700)(-8200 2850);
WIRE 16 -1 (-8200 2700)(-8700 2700);
FORCEPROP 2 LAST SIG_NAME I3C_SPD_DDRGL_CPU1_SDA
J 0
(-8710 2710);
DISPLAY 0.489362 (-8710 2710);
WIRE 16 -1 (-7400 2900)(-8575 2900);
FORCEPROP 2 LAST SIG_NAME PD_CHL_CPU1_DIMM_SAA
J 0
(-8550 2910);
DISPLAY 0.489362 (-8550 2910);
WIRE 16 -1 (-8475 2950)(-7400 2950);
WIRE 16 -1 (-8475 3350)(-8475 2950);
WIRE 16 -1 (-8475 3375)(-8475 3350);
WIRE 16 -1 (-8575 3350)(-8475 3350);
WIRE 16 -1 (-8575 3325)(-8575 3350);
DOT 1 (-2100 4575);
DOT 1 (-2100 5275);
DOT 1 (-2225 6050);
DOT 1 (-2800 6050);
DOT 1 (-2800 5625);
DOT 1 (-8325 2150);
DOT 1 (-300 5275);
DOT 1 (-300 5225);
DOT 1 (-300 5175);
DOT 1 (-300 5125);
DOT 1 (-300 5075);
DOT 1 (-300 5025);
DOT 1 (-300 4975);
DOT 1 (-300 4925);
DOT 1 (-300 4875);
DOT 1 (-300 4825);
DOT 1 (-300 4775);
DOT 1 (-300 4725);
DOT 1 (-300 4675);
DOT 1 (-300 4575);
DOT 1 (-300 4625);
DOT 1 (-300 4525);
DOT 1 (-300 4425);
DOT 1 (-300 4475);
DOT 1 (-300 4325);
DOT 1 (-300 4375);
DOT 1 (-300 4275);
DOT 1 (-300 4225);
DOT 1 (-300 4175);
DOT 1 (-300 4075);
DOT 1 (-300 4125);
DOT 1 (-300 4025);
DOT 1 (-300 3975);
DOT 1 (-300 3925);
DOT 1 (-300 3875);
DOT 1 (-300 3825);
DOT 1 (-2100 5325);
DOT 1 (-2100 5075);
DOT 1 (-2100 5125);
DOT 1 (-2100 4975);
DOT 1 (-2100 5025);
DOT 1 (-2100 4925);
DOT 1 (-2100 4875);
DOT 1 (-2100 4825);
DOT 1 (-2100 4725);
DOT 1 (-2100 4775);
DOT 1 (-2100 4675);
DOT 1 (-2100 4625);
DOT 1 (-2100 4425);
DOT 1 (-2100 4475);
DOT 1 (-2100 4525);
DOT 1 (-2100 4325);
DOT 1 (-2100 4375);
DOT 1 (-2100 4175);
DOT 1 (-2100 4225);
DOT 1 (-2100 4275);
DOT 1 (-2100 4075);
DOT 1 (-2100 4125);
DOT 1 (-2100 3925);
DOT 1 (-2100 3975);
DOT 1 (-2100 4025);
DOT 1 (-2100 3825);
DOT 1 (-2100 3875);
DOT 1 (-2100 3775);
DOT 1 (-300 3775);
DOT 1 (-300 3675);
DOT 1 (-300 3725);
DOT 1 (-300 3625);
DOT 1 (-300 3575);
DOT 1 (-300 3525);
DOT 1 (-300 3425);
DOT 1 (-300 3475);
DOT 1 (-300 3375);
DOT 1 (-300 3325);
DOT 1 (-300 3275);
DOT 1 (-300 3175);
DOT 1 (-300 3225);
DOT 1 (-300 3125);
DOT 1 (-300 3075);
DOT 1 (-300 3025);
DOT 1 (-300 2925);
DOT 1 (-300 2975);
DOT 1 (-300 2775);
DOT 1 (-300 2825);
DOT 1 (-300 2875);
DOT 1 (-300 2725);
DOT 1 (-300 2675);
DOT 1 (-300 2625);
DOT 1 (-300 2525);
DOT 1 (-300 2575);
DOT 1 (-300 2475);
DOT 1 (-300 2425);
DOT 1 (-300 2375);
DOT 1 (-300 2275);
DOT 1 (-300 2325);
DOT 1 (-300 2175);
DOT 1 (-300 2225);
DOT 1 (-300 2025);
DOT 1 (-300 2075);
DOT 1 (-300 1975);
DOT 1 (-2100 3675);
DOT 1 (-2100 3725);
DOT 1 (-2100 3575);
DOT 1 (-2100 3625);
DOT 1 (-2100 3525);
DOT 1 (-2100 3425);
DOT 1 (-2100 3475);
DOT 1 (-2100 3275);
DOT 1 (-2100 3325);
DOT 1 (-2100 3375);
DOT 1 (-2100 3175);
DOT 1 (-2100 3225);
DOT 1 (-2100 3025);
DOT 1 (-2100 3075);
DOT 1 (-2100 3125);
DOT 1 (-2100 2925);
DOT 1 (-2100 2975);
DOT 1 (-2100 2775);
DOT 1 (-2100 2825);
DOT 1 (-2100 2875);
DOT 1 (-2100 2675);
DOT 1 (-2100 2725);
DOT 1 (-2100 2625);
DOT 1 (-2100 2525);
DOT 1 (-2100 2575);
DOT 1 (-2100 2425);
DOT 1 (-2100 2475);
DOT 1 (-2100 2375);
DOT 1 (-2100 2275);
DOT 1 (-2100 2325);
DOT 1 (-2100 2125);
DOT 1 (-2100 2175);
DOT 1 (-2100 2225);
DOT 1 (-2100 2075);
DOT 1 (-8475 3350);
QUIT
